FILE_TYPE = MACRO_DRAWING;
SET COLOR_WIRE YELLOW;
SET COLOR_PROP ORANGE;
SET COLOR_DOT WHITE;
SET COLOR_ARC YELLOW;
SET COLOR_BODY GREEN;
SET COLOR_NOTE PURPLE;
SET PROP_DISPLAY VALUE;
SET PAGE_NUMBER P149;
FORCEADD SN74AVC2T245RSWR..1
R 2
(-7000 2100);
FORCEPROP 1 LAST LOCATION U147
J 2
(-6750 2600);
DISPLAY 0.489362 (-6750 2600);
PAINT SKYBLUE (-6750 2600);
FORCEPROP 0 LAST $SEC 1
J 0
(-6775 2775);
PAINT MONO (-6775 2775);
DISPLAY INVISIBLE (-6775 2775);
FORCEPROP 0 LAST CDS_SEC 1
J 0
(-6775 2775);
PAINT MONO (-6775 2775);
DISPLAY INVISIBLE (-6775 2775);
FORCEPROP 0 LASTPIN (-7400 2225) $PN 8
J 2
(-7410 2235);
DISPLAY 0.489362 (-7410 2235);
PAINT MONO (-7410 2235);
FORCEPROP 0 LASTPIN (-7400 2075) $PN 9
J 2
(-7410 2085);
DISPLAY 0.489362 (-7410 2085);
PAINT MONO (-7410 2085);
FORCEPROP 0 LASTPIN (-6600 2175) $PN 5
J 0
(-6590 2185);
DISPLAY 0.489362 (-6590 2185);
PAINT MONO (-6590 2185);
FORCEPROP 0 LASTPIN (-6600 2025) $PN 4
J 0
(-6590 2035);
DISPLAY 0.489362 (-6590 2035);
PAINT MONO (-6590 2035);
FORCEPROP 0 LASTPIN (-7400 2175) $PN 10
J 2
(-7410 2185);
DISPLAY 0.489362 (-7410 2185);
PAINT MONO (-7410 2185);
FORCEPROP 0 LASTPIN (-7400 2025) $PN 1
J 2
(-7410 2035);
DISPLAY 0.489362 (-7410 2035);
PAINT MONO (-7410 2035);
FORCEPROP 0 LASTPIN (-7400 1775) $PN 3
J 2
(-7410 1785);
DISPLAY 0.489362 (-7410 1785);
PAINT MONO (-7410 1785);
FORCEPROP 0 LASTPIN (-7400 1925) $PN 2
J 2
(-7410 1935);
DISPLAY 0.489362 (-7410 1935);
PAINT MONO (-7410 1935);
FORCEPROP 0 LASTPIN (-6600 2425) $PN 7
J 0
(-6590 2435);
DISPLAY 0.489362 (-6590 2435);
PAINT MONO (-6590 2435);
FORCEPROP 0 LASTPIN (-6600 2375) $PN 6
J 0
(-6590 2385);
DISPLAY 0.489362 (-6590 2385);
PAINT MONO (-6590 2385);
FORCEPROP 1 LAST MATERIAL IC
J 2
(-6755 2482);
DISPLAY 0.489362 (-6755 2482);
PAINT SKYBLUE (-6755 2482);
FORCEPROP 2 LAST PART_TYPE SMLF
J 2
(-6750 2725);
PAINT MONO (-6750 2725);
FORCEPROP 2 LAST VALUE SN74AVC2T245RSWR
J 2
(-6750 2650);
DISPLAY 0.489362 (-6750 2650);
PAINT SKYBLUE (-6750 2650);
FORCEPROP 1 LAST NEEDS_NO_SIZE TRUE
J 2
(-7250 1782);
DISPLAY 0.723404 (-7250 1782);
PAINT GREEN (-7250 1782);
DISPLAY INVISIBLE (-7250 1782);
FORCEPROP 2 LAST CDS_LIB pure_quanta
J 2
(-7000 2100);
PAINT MONO (-7000 2100);
DISPLAY INVISIBLE (-7000 2100);
FORCEPROP 1 LAST CDS_LMAN_SYM_OUTLINE -250,375,250,-375
J 2
(-7000 2100);
DISPLAY 0.468085 (-7000 2100);
PAINT GREEN (-7000 2100);
DISPLAY INVISIBLE (-7000 2100);
FORCEPROP 1 LAST PATH I1
J 2
(-7250 1725);
DISPLAY 0.723404 (-7250 1725);
PAINT GREEN (-7250 1725);
DISPLAY INVISIBLE (-7250 1725);
FORCEPROP 1 LAST PART_NUMBER AL02T245000
J 2
(-6755 2551);
DISPLAY 0.489362 (-6755 2551);
PAINT SKYBLUE (-6755 2551);
DISPLAY INVISIBLE (-6755 2551);
FORCEADD Q_CAP..1
(-2650 4550);
FORCEPROP 1 LAST LOCATION C1509
J 0
(-2550 4700);
DISPLAY 0.489362 (-2550 4700);
PAINT SKYBLUE (-2550 4700);
FORCEPROP 2 LAST $SEC 1
J 0
(-2600 4750);
PAINT MONO (-2600 4750);
DISPLAY INVISIBLE (-2600 4750);
FORCEPROP 2 LAST CDS_SEC 1
J 0
(-2600 4750);
PAINT MONO (-2600 4750);
DISPLAY INVISIBLE (-2600 4750);
FORCEPROP 1 LASTPIN (-2650 4650) $PN 1
J 0
(-2640 4630);
DISPLAY 0.489362 (-2640 4630);
PAINT GREEN (-2640 4630);
FORCEPROP 1 LASTPIN (-2650 4450) $PN 2
J 0
(-2640 4430);
DISPLAY 0.489362 (-2640 4430);
PAINT GREEN (-2640 4430);
FORCEPROP 1 LAST PACK_TYPE C0402
J 0
(-2550 4400);
DISPLAY 0.489362 (-2550 4400);
PAINT SKYBLUE (-2550 4400);
FORCEPROP 1 LAST VOLTAGE 16V
J 0
(-2550 4600);
DISPLAY 0.489362 (-2550 4600);
PAINT SKYBLUE (-2550 4600);
FORCEPROP 1 LAST VALUE 0.1UF
J 0
(-2550 4650);
DISPLAY 0.489362 (-2550 4650);
PAINT SKYBLUE (-2550 4650);
FORCEPROP 1 LAST TOLERANCE 10%
J 0
(-2550 4550);
DISPLAY 0.489362 (-2550 4550);
PAINT SKYBLUE (-2550 4550);
FORCEPROP 1 LAST MATERIAL X7R
J 0
(-2550 4500);
DISPLAY 0.489362 (-2550 4500);
PAINT SKYBLUE (-2550 4500);
FORCEPROP 2 LAST CDS_LIB pure_quanta
J 0
(-2650 4550);
DISPLAY INVISIBLE (-2650 4550);
FORCEPROP 1 LAST PATH I10
J 0
(-2600 4700);
DISPLAY 0.978723 (-2600 4700);
PAINT WHITE (-2600 4700);
DISPLAY INVISIBLE (-2600 4700);
FORCEPROP 1 LAST PART_NUMBER CH4103K1B08
J 0
(-2550 4450);
DISPLAY 0.489362 (-2550 4450);
PAINT SKYBLUE (-2550 4450);
DISPLAY INVISIBLE (-2550 4450);
FORCEADD Q_RES..2
(-6425 3550);
FORCEPROP 1 LAST LOCATION R617
J 0
(-6325 3725);
DISPLAY 0.489362 (-6325 3725);
PAINT SKYBLUE (-6325 3725);
FORCEPROP 0 LAST $SEC 1
J 0
(-6375 3725);
DISPLAY 0.680851 (-6375 3725);
PAINT MONO (-6375 3725);
DISPLAY INVISIBLE (-6375 3725);
FORCEPROP 0 LAST CDS_SEC 1
J 0
(-6375 3725);
DISPLAY 1.021277 (-6375 3725);
DISPLAY INVISIBLE (-6375 3725);
FORCEPROP 1 LASTPIN (-6425 3650) $PN 1
J 0
(-6420 3612);
DISPLAY 0.489362 (-6420 3612);
PAINT MONO (-6420 3612);
FORCEPROP 1 LASTPIN (-6425 3450) $PN 2
J 0
(-6420 3460);
DISPLAY 0.489362 (-6420 3460);
PAINT MONO (-6420 3460);
FORCEPROP 1 LAST MATERIAL CHIP
J 0
(-6325 3625);
DISPLAY 0.489362 (-6325 3625);
PAINT SKYBLUE (-6325 3625);
FORCEPROP 1 LAST WATTAGE 1/16W
J 0
(-6320 3525);
DISPLAY 0.489362 (-6320 3525);
PAINT SKYBLUE (-6320 3525);
FORCEPROP 1 LAST TOLERANCE 5%
J 0
(-6320 3575);
DISPLAY 0.489362 (-6320 3575);
PAINT SKYBLUE (-6320 3575);
FORCEPROP 1 LAST VALUE 4.7K
J 0
(-6320 3675);
DISPLAY 0.489362 (-6320 3675);
PAINT SKYBLUE (-6320 3675);
FORCEPROP 1 LAST PACK_TYPE 0402LF
J 0
(-6320 3475);
DISPLAY 0.489362 (-6320 3475);
PAINT SKYBLUE (-6320 3475);
FORCEPROP 2 LAST CDS_LIB pure_quanta
J 0
(-6425 3550);
DISPLAY INVISIBLE (-6425 3550);
FORCEPROP 1 LAST PATH I101
J 0
(-6375 3725);
DISPLAY 0.978723 (-6375 3725);
PAINT WHITE (-6375 3725);
DISPLAY INVISIBLE (-6375 3725);
FORCEPROP 1 LAST PART_NUMBER CS24702JB10
J 0
(-6320 3425);
DISPLAY 0.489362 (-6320 3425);
PAINT SKYBLUE (-6320 3425);
DISPLAY INVISIBLE (-6320 3425);
FORCEADD MOSFET_N..1
(-7525 700);
FORCEPROP 1 LAST LOCATION Q62
J 0
(-7400 745);
DISPLAY 0.489362 (-7400 745);
PAINT SKYBLUE (-7400 745);
FORCEPROP 0 LAST $SEC 1
J 0
(-7400 875);
DISPLAY 0.680851 (-7400 875);
PAINT MONO (-7400 875);
DISPLAY INVISIBLE (-7400 875);
FORCEPROP 0 LAST CDS_SEC 1
J 0
(-7400 900);
PAINT MONO (-7400 900);
DISPLAY INVISIBLE (-7400 900);
FORCEPROP 1 LASTPIN (-7475 800) $PN D
R 1
J 0
(-7475 793);
DISPLAY 0.489362 (-7475 793);
PAINT MONO (-7475 793);
FORCEPROP 1 LASTPIN (-7625 600) $PN G
J 2
(-7615 603);
DISPLAY 0.489362 (-7615 603);
PAINT MONO (-7615 603);
FORCEPROP 1 LASTPIN (-7475 500) $PN S
R 1
J 2
(-7475 513);
DISPLAY 0.489362 (-7475 513);
PAINT MONO (-7475 513);
FORCEPROP 2 LAST PART_TYPE SMLF
J 0
(-7675 825);
PAINT MONO (-7675 825);
FORCEPROP 1 LAST MATERIAL IC
J 0
(-7400 585);
DISPLAY 0.489362 (-7400 585);
PAINT SKYBLUE (-7400 585);
FORCEPROP 1 LAST VALUE BSS138K
J 0
(-7400 825);
DISPLAY 0.489362 (-7400 825);
PAINT SKYBLUE (-7400 825);
FORCEPROP 1 LAST PACK_TYPE SMLF
J 0
(-7500 450);
DISPLAY 0.723404 (-7500 450);
PAINT SKYBLUE (-7500 450);
DISPLAY INVISIBLE (-7500 450);
FORCEPROP 1 LAST CDS_LMAN_SYM_OUTLINE -50,50,100,-150
J 0
(-7525 700);
DISPLAY 0.468085 (-7525 700);
PAINT GREEN (-7525 700);
DISPLAY INVISIBLE (-7525 700);
FORCEPROP 2 LAST CDS_LIB pure_quanta
J 0
(-7525 700);
DISPLAY INVISIBLE (-7525 700);
FORCEPROP 0 LAST MANUF_PN BSS138K
J 0
(-7850 950);
DISPLAY 1.021277 (-7850 950);
DISPLAY INVISIBLE (-7850 950);
FORCEPROP 0 LAST PATH I102
J 0
(-7850 900);
DISPLAY 1.021277 (-7850 900);
DISPLAY INVISIBLE (-7850 900);
FORCEPROP 1 LAST PART_NUMBER BAM138K0000
J 0
(-7400 665);
DISPLAY 0.489362 (-7400 665);
PAINT SKYBLUE (-7400 665);
DISPLAY INVISIBLE (-7400 665);
FORCEADD Q_RES..1
(-3975 5850);
FORCEPROP 1 LAST LOCATION R1354
J 0
(-4175 5850);
DISPLAY 0.489362 (-4175 5850);
PAINT SKYBLUE (-4175 5850);
FORCEPROP 0 LAST $SEC 1
J 0
(-4100 5900);
DISPLAY 0.680851 (-4100 5900);
PAINT MONO (-4100 5900);
DISPLAY INVISIBLE (-4100 5900);
FORCEPROP 0 LAST CDS_SEC 1
J 0
(-4100 5900);
DISPLAY 0.680851 (-4100 5900);
DISPLAY INVISIBLE (-4100 5900);
FORCEPROP 1 LASTPIN (-4075 5850) $PN 1
J 0
(-4063 5862);
DISPLAY 0.489362 (-4063 5862);
PAINT MONO (-4063 5862);
FORCEPROP 1 LASTPIN (-3875 5850) $PN 2
J 0
(-3913 5862);
DISPLAY 0.489362 (-3913 5862);
PAINT MONO (-3913 5862);
FORCEPROP 1 LAST VALUE 0
J 2
(-3825 5850);
DISPLAY 0.489362 (-3825 5850);
PAINT SKYBLUE (-3825 5850);
FORCEPROP 2 LAST CDS_LIB pure_quanta
J 0
(-3975 5850);
DISPLAY INVISIBLE (-3975 5850);
FORCEPROP 1 LAST WATTAGE 1/16W
J 2
(-4000 5700);
DISPLAY 0.978723 (-4000 5700);
PAINT SKYBLUE (-4000 5700);
DISPLAY INVISIBLE (-4000 5700);
FORCEPROP 1 LAST MATERIAL CHIP
J 0
(-3750 5850);
DISPLAY 0.617021 (-3750 5850);
PAINT SKYBLUE (-3750 5850);
DISPLAY INVISIBLE (-3750 5850);
FORCEPROP 1 LAST TOLERANCE 5%
J 0
(-3975 5750);
DISPLAY 0.978723 (-3975 5750);
PAINT SKYBLUE (-3975 5750);
DISPLAY INVISIBLE (-3975 5750);
FORCEPROP 1 LAST PACK_TYPE 0402LF
J 0
(-3725 5700);
DISPLAY 0.978723 (-3725 5700);
PAINT SKYBLUE (-3725 5700);
DISPLAY INVISIBLE (-3725 5700);
FORCEPROP 1 LAST PATH I109
J 0
(-4025 6000);
DISPLAY 0.978723 (-4025 6000);
PAINT WHITE (-4025 6000);
DISPLAY INVISIBLE (-4025 6000);
FORCEPROP 1 LAST PART_NUMBER CS00002JB13
J 0
(-4025 5950);
DISPLAY 0.978723 (-4025 5950);
PAINT SKYBLUE (-4025 5950);
DISPLAY INVISIBLE (-4025 5950);
FORCEADD GND..1
(-2650 4375);
FORCEPROP 3 LASTPIN (-2650 4425) SIG_NAME GND\g
J 0
(-2640 4435);
DISPLAY 0.659574 (-2640 4435);
PAINT MONO (-2640 4435);
DISPLAY INVISIBLE (-2640 4435);
FORCEPROP 1 LAST SIZE 1B
J 0
(-2575 4325);
DISPLAY 0.872340 (-2575 4325);
PAINT GREEN (-2575 4325);
DISPLAY INVISIBLE (-2575 4325);
FORCEPROP 2 LAST CDS_LIB pure_quanta_power
J 0
(-2650 4375);
DISPLAY INVISIBLE (-2650 4375);
FORCEPROP 1 LAST HDL_POWER GND
J 0
(-2650 4525);
DISPLAY 0.872340 (-2650 4525);
PAINT GREEN (-2650 4525);
DISPLAY INVISIBLE (-2650 4525);
FORCEPROP 1 LAST PATH I11
J 0
(-2575 4375);
DISPLAY 0.872340 (-2575 4375);
PAINT AQUA (-2575 4375);
DISPLAY INVISIBLE (-2575 4375);
FORCEADD GND..1
(-3675 5100);
FORCEPROP 3 LASTPIN (-3675 5150) SIG_NAME GND\g
J 0
(-3665 5160);
DISPLAY 0.659574 (-3665 5160);
PAINT MONO (-3665 5160);
DISPLAY INVISIBLE (-3665 5160);
FORCEPROP 2 LAST CDS_LIB pure_quanta_power
J 0
(-3675 5100);
DISPLAY INVISIBLE (-3675 5100);
FORCEPROP 1 LAST SIZE 1B
J 0
(-3600 5050);
DISPLAY 0.872340 (-3600 5050);
PAINT GREEN (-3600 5050);
DISPLAY INVISIBLE (-3600 5050);
FORCEPROP 1 LAST HDL_POWER GND
J 0
(-3675 5250);
DISPLAY 0.872340 (-3675 5250);
PAINT GREEN (-3675 5250);
DISPLAY INVISIBLE (-3675 5250);
FORCEPROP 1 LAST PATH I110
J 0
(-3600 5100);
DISPLAY 0.872340 (-3600 5100);
PAINT AQUA (-3600 5100);
DISPLAY INVISIBLE (-3600 5100);
FORCEADD Q_RES..2
(-3650 6125);
FORCEPROP 1 LAST LOCATION R1624
J 0
(-3625 6225);
DISPLAY 0.489362 (-3625 6225);
PAINT SKYBLUE (-3625 6225);
FORCEPROP 2 LAST $SEC 1
J 0
(-3600 6350);
DISPLAY 0.680851 (-3600 6350);
PAINT MONO (-3600 6350);
DISPLAY INVISIBLE (-3600 6350);
FORCEPROP 2 LAST CDS_SEC 1
J 0
(-3600 6350);
DISPLAY 1.021277 (-3600 6350);
DISPLAY INVISIBLE (-3600 6350);
FORCEPROP 1 LASTPIN (-3650 6225) $PN 1
J 0
(-3645 6187);
DISPLAY 0.489362 (-3645 6187);
FORCEPROP 1 LASTPIN (-3650 6025) $PN 2
J 0
(-3645 6035);
DISPLAY 0.489362 (-3645 6035);
FORCEPROP 1 LAST VALUE 1K
J 0
(-3625 6175);
DISPLAY 0.489362 (-3625 6175);
PAINT SKYBLUE (-3625 6175);
FORCEPROP 1 LAST TOLERANCE 1%
J 0
(-3625 6125);
DISPLAY 0.489362 (-3625 6125);
PAINT SKYBLUE (-3625 6125);
FORCEPROP 2 LAST CDS_LIB pure_quanta
J 0
(-3650 6125);
DISPLAY INVISIBLE (-3650 6125);
FORCEPROP 1 LAST WATTAGE 1/16W
J 0
(-3625 6075);
DISPLAY 0.489362 (-3625 6075);
PAINT SKYBLUE (-3625 6075);
DISPLAY INVISIBLE (-3625 6075);
FORCEPROP 1 LAST MATERIAL CHIP
J 0
(-3625 6025);
DISPLAY 0.489362 (-3625 6025);
PAINT SKYBLUE (-3625 6025);
DISPLAY INVISIBLE (-3625 6025);
FORCEPROP 1 LAST PACK_TYPE 0402LF
J 0
(-3625 5975);
DISPLAY 0.489362 (-3625 5975);
PAINT SKYBLUE (-3625 5975);
DISPLAY INVISIBLE (-3625 5975);
FORCEPROP 1 LAST PATH I111
J 0
(-3600 6300);
DISPLAY 0.978723 (-3600 6300);
PAINT WHITE (-3600 6300);
DISPLAY INVISIBLE (-3600 6300);
FORCEPROP 1 LAST PART_NUMBER CS21002FB06
J 0
(-3610 6000);
DISPLAY 0.617021 (-3610 6000);
PAINT SKYBLUE (-3610 6000);
DISPLAY INVISIBLE (-3610 6000);
FORCEADD Q_RES..2
(-3675 5325);
FORCEPROP 1 LAST LOCATION R1629
J 0
(-3600 5375);
DISPLAY 0.489362 (-3600 5375);
PAINT SKYBLUE (-3600 5375);
FORCEPROP 0 LAST $SEC 1
J 0
(-3550 5550);
PAINT MONO (-3550 5550);
DISPLAY INVISIBLE (-3550 5550);
FORCEPROP 0 LAST CDS_SEC 1
J 0
(-3550 5550);
PAINT MONO (-3550 5550);
DISPLAY INVISIBLE (-3550 5550);
FORCEPROP 1 LASTPIN (-3675 5425) $PN 1
J 0
(-3670 5387);
DISPLAY 0.489362 (-3670 5387);
PAINT GREEN (-3670 5387);
FORCEPROP 1 LASTPIN (-3675 5225) $PN 2
J 0
(-3670 5235);
DISPLAY 0.489362 (-3670 5235);
PAINT GREEN (-3670 5235);
FORCEPROP 1 LAST WATTAGE 1/16W
J 0
(-3600 5275);
DISPLAY 0.489362 (-3600 5275);
PAINT SKYBLUE (-3600 5275);
FORCEPROP 1 LAST MATERIAL CHIP
J 0
(-3600 5325);
DISPLAY 0.489362 (-3600 5325);
PAINT SKYBLUE (-3600 5325);
FORCEPROP 1 LAST VALUE 1K
J 0
(-3600 5350);
DISPLAY 0.489362 (-3600 5350);
PAINT SKYBLUE (-3600 5350);
FORCEPROP 1 LAST PACK_TYPE 0402LF
J 0
(-3600 5250);
DISPLAY 0.489362 (-3600 5250);
PAINT SKYBLUE (-3600 5250);
FORCEPROP 1 LAST TOLERANCE 1%
J 0
(-3600 5300);
DISPLAY 0.489362 (-3600 5300);
PAINT SKYBLUE (-3600 5300);
FORCEPROP 2 LAST CDS_LIB pure_quanta
J 0
(-3675 5325);
PAINT MONO (-3675 5325);
DISPLAY INVISIBLE (-3675 5325);
FORCEPROP 1 LAST PATH I112
J 0
(-3625 5500);
DISPLAY 0.978723 (-3625 5500);
PAINT WHITE (-3625 5500);
DISPLAY INVISIBLE (-3625 5500);
FORCEPROP 1 LAST PART_NUMBER CS21002FB06
J 0
(-3600 5225);
DISPLAY 0.489362 (-3600 5225);
PAINT SKYBLUE (-3600 5225);
DISPLAY INVISIBLE (-3600 5225);
FORCEADD Q_RES..1
(-3025 5600);
FORCEPROP 1 LAST LOCATION R1631
J 0
(-3250 5600);
DISPLAY 0.489362 (-3250 5600);
PAINT SKYBLUE (-3250 5600);
FORCEPROP 2 LAST $SEC 1
J 0
(-3075 5800);
DISPLAY 0.680851 (-3075 5800);
PAINT MONO (-3075 5800);
DISPLAY INVISIBLE (-3075 5800);
FORCEPROP 2 LAST CDS_SEC 1
J 0
(-3075 5800);
DISPLAY 1.021277 (-3075 5800);
DISPLAY INVISIBLE (-3075 5800);
FORCEPROP 1 LASTPIN (-3125 5600) $PN 1
J 0
(-3113 5612);
DISPLAY 0.489362 (-3113 5612);
FORCEPROP 1 LASTPIN (-2925 5600) $PN 2
J 0
(-2963 5612);
DISPLAY 0.489362 (-2963 5612);
FORCEPROP 1 LAST VALUE 33
J 2
(-2850 5600);
DISPLAY 0.489362 (-2850 5600);
PAINT SKYBLUE (-2850 5600);
FORCEPROP 2 LAST CDS_LIB pure_quanta
J 0
(-3025 5600);
DISPLAY INVISIBLE (-3025 5600);
FORCEPROP 1 LAST WATTAGE 1/16W
J 2
(-3050 5450);
DISPLAY 0.978723 (-3050 5450);
PAINT SKYBLUE (-3050 5450);
DISPLAY INVISIBLE (-3050 5450);
FORCEPROP 1 LAST MATERIAL CHIP
J 0
(-2800 5600);
DISPLAY 0.489362 (-2800 5600);
PAINT SKYBLUE (-2800 5600);
DISPLAY INVISIBLE (-2800 5600);
FORCEPROP 1 LAST TOLERANCE 5%
J 0
(-3025 5500);
DISPLAY 0.978723 (-3025 5500);
PAINT SKYBLUE (-3025 5500);
DISPLAY INVISIBLE (-3025 5500);
FORCEPROP 1 LAST PACK_TYPE 0402LF
J 0
(-2950 5550);
DISPLAY 0.489362 (-2950 5550);
PAINT SKYBLUE (-2950 5550);
DISPLAY INVISIBLE (-2950 5550);
FORCEPROP 1 LAST PATH I113
J 0
(-3075 5750);
DISPLAY 0.978723 (-3075 5750);
PAINT WHITE (-3075 5750);
DISPLAY INVISIBLE (-3075 5750);
FORCEPROP 1 LAST PART_NUMBER CS03302JB10
J 0
(-3075 5700);
DISPLAY 0.978723 (-3075 5700);
PAINT SKYBLUE (-3075 5700);
DISPLAY INVISIBLE (-3075 5700);
FORCEADD Q_RES..1
(-3025 5550);
FORCEPROP 1 LAST LOCATION R1632
J 0
(-3250 5550);
DISPLAY 0.489362 (-3250 5550);
PAINT SKYBLUE (-3250 5550);
FORCEPROP 2 LAST $SEC 1
J 0
(-3075 5750);
DISPLAY 0.680851 (-3075 5750);
PAINT MONO (-3075 5750);
DISPLAY INVISIBLE (-3075 5750);
FORCEPROP 2 LAST CDS_SEC 1
J 0
(-3075 5750);
DISPLAY 1.021277 (-3075 5750);
DISPLAY INVISIBLE (-3075 5750);
FORCEPROP 1 LASTPIN (-3125 5550) $PN 1
J 0
(-3113 5562);
DISPLAY 0.489362 (-3113 5562);
FORCEPROP 1 LASTPIN (-2925 5550) $PN 2
J 0
(-2963 5562);
DISPLAY 0.489362 (-2963 5562);
FORCEPROP 1 LAST VALUE 33
J 2
(-2850 5550);
DISPLAY 0.489362 (-2850 5550);
PAINT SKYBLUE (-2850 5550);
FORCEPROP 2 LAST CDS_LIB pure_quanta
J 0
(-3025 5550);
DISPLAY INVISIBLE (-3025 5550);
FORCEPROP 1 LAST WATTAGE 1/16W
J 2
(-3050 5400);
DISPLAY 0.978723 (-3050 5400);
PAINT SKYBLUE (-3050 5400);
DISPLAY INVISIBLE (-3050 5400);
FORCEPROP 1 LAST MATERIAL CHIP
J 0
(-3075 5500);
DISPLAY 0.489362 (-3075 5500);
PAINT SKYBLUE (-3075 5500);
DISPLAY INVISIBLE (-3075 5500);
FORCEPROP 1 LAST TOLERANCE 5%
J 0
(-3025 5450);
DISPLAY 0.978723 (-3025 5450);
PAINT SKYBLUE (-3025 5450);
DISPLAY INVISIBLE (-3025 5450);
FORCEPROP 1 LAST PACK_TYPE 0402LF
J 0
(-2950 5500);
DISPLAY 0.489362 (-2950 5500);
PAINT SKYBLUE (-2950 5500);
DISPLAY INVISIBLE (-2950 5500);
FORCEPROP 1 LAST PATH I114
J 0
(-3075 5700);
DISPLAY 0.978723 (-3075 5700);
PAINT WHITE (-3075 5700);
DISPLAY INVISIBLE (-3075 5700);
FORCEPROP 1 LAST PART_NUMBER CS03302JB10
J 0
(-3075 5650);
DISPLAY 0.978723 (-3075 5650);
PAINT SKYBLUE (-3075 5650);
DISPLAY INVISIBLE (-3075 5650);
FORCEADD Q_RES..2
(-3525 6125);
FORCEPROP 1 LAST LOCATION R1626
J 0
(-3500 6225);
DISPLAY 0.489362 (-3500 6225);
PAINT SKYBLUE (-3500 6225);
FORCEPROP 2 LAST $SEC 1
J 0
(-3475 6350);
DISPLAY 0.680851 (-3475 6350);
PAINT MONO (-3475 6350);
DISPLAY INVISIBLE (-3475 6350);
FORCEPROP 2 LAST CDS_SEC 1
J 0
(-3475 6350);
DISPLAY 1.021277 (-3475 6350);
DISPLAY INVISIBLE (-3475 6350);
FORCEPROP 1 LASTPIN (-3525 6225) $PN 1
J 0
(-3520 6187);
DISPLAY 0.489362 (-3520 6187);
FORCEPROP 1 LASTPIN (-3525 6025) $PN 2
J 0
(-3520 6035);
DISPLAY 0.489362 (-3520 6035);
FORCEPROP 1 LAST VALUE 1K
J 0
(-3500 6175);
DISPLAY 0.489362 (-3500 6175);
PAINT SKYBLUE (-3500 6175);
FORCEPROP 1 LAST TOLERANCE 1%
J 0
(-3500 6125);
DISPLAY 0.489362 (-3500 6125);
PAINT SKYBLUE (-3500 6125);
FORCEPROP 2 LAST CDS_LIB pure_quanta
J 0
(-3525 6125);
DISPLAY INVISIBLE (-3525 6125);
FORCEPROP 1 LAST WATTAGE 1/16W
J 0
(-3500 6075);
DISPLAY 0.489362 (-3500 6075);
PAINT SKYBLUE (-3500 6075);
DISPLAY INVISIBLE (-3500 6075);
FORCEPROP 1 LAST MATERIAL CHIP
J 0
(-3500 6025);
DISPLAY 0.489362 (-3500 6025);
PAINT SKYBLUE (-3500 6025);
DISPLAY INVISIBLE (-3500 6025);
FORCEPROP 1 LAST PACK_TYPE 0402LF
J 0
(-3500 5975);
DISPLAY 0.489362 (-3500 5975);
PAINT SKYBLUE (-3500 5975);
DISPLAY INVISIBLE (-3500 5975);
FORCEPROP 1 LAST PATH I115
J 0
(-3475 6300);
DISPLAY 0.978723 (-3475 6300);
PAINT WHITE (-3475 6300);
DISPLAY INVISIBLE (-3475 6300);
FORCEPROP 1 LAST PART_NUMBER CS21002FB06
J 0
(-3485 6000);
DISPLAY 0.617021 (-3485 6000);
PAINT SKYBLUE (-3485 6000);
DISPLAY INVISIBLE (-3485 6000);
FORCEADD Q_RES..2
(-3400 6125);
FORCEPROP 1 LAST LOCATION R1627
J 0
(-3375 6225);
DISPLAY 0.489362 (-3375 6225);
PAINT SKYBLUE (-3375 6225);
FORCEPROP 2 LAST $SEC 1
J 0
(-3350 6350);
DISPLAY 0.680851 (-3350 6350);
PAINT MONO (-3350 6350);
DISPLAY INVISIBLE (-3350 6350);
FORCEPROP 2 LAST CDS_SEC 1
J 0
(-3350 6350);
DISPLAY 1.021277 (-3350 6350);
DISPLAY INVISIBLE (-3350 6350);
FORCEPROP 1 LASTPIN (-3400 6225) $PN 1
J 0
(-3395 6187);
DISPLAY 0.489362 (-3395 6187);
FORCEPROP 1 LASTPIN (-3400 6025) $PN 2
J 0
(-3395 6035);
DISPLAY 0.489362 (-3395 6035);
FORCEPROP 1 LAST VALUE 1K
J 0
(-3375 6175);
DISPLAY 0.489362 (-3375 6175);
PAINT SKYBLUE (-3375 6175);
FORCEPROP 1 LAST TOLERANCE 1%
J 0
(-3375 6125);
DISPLAY 0.489362 (-3375 6125);
PAINT SKYBLUE (-3375 6125);
FORCEPROP 2 LAST CDS_LIB pure_quanta
J 0
(-3400 6125);
DISPLAY INVISIBLE (-3400 6125);
FORCEPROP 1 LAST WATTAGE 1/16W
J 0
(-3375 6075);
DISPLAY 0.489362 (-3375 6075);
PAINT SKYBLUE (-3375 6075);
DISPLAY INVISIBLE (-3375 6075);
FORCEPROP 1 LAST MATERIAL CHIP
J 0
(-3375 6025);
DISPLAY 0.489362 (-3375 6025);
PAINT SKYBLUE (-3375 6025);
DISPLAY INVISIBLE (-3375 6025);
FORCEPROP 1 LAST PACK_TYPE 0402LF
J 0
(-3375 5975);
DISPLAY 0.489362 (-3375 5975);
PAINT SKYBLUE (-3375 5975);
DISPLAY INVISIBLE (-3375 5975);
FORCEPROP 1 LAST PATH I116
J 0
(-3350 6300);
DISPLAY 0.978723 (-3350 6300);
PAINT WHITE (-3350 6300);
DISPLAY INVISIBLE (-3350 6300);
FORCEPROP 1 LAST PART_NUMBER CS21002FB06
J 0
(-3360 6000);
DISPLAY 0.617021 (-3360 6000);
PAINT SKYBLUE (-3360 6000);
DISPLAY INVISIBLE (-3360 6000);
FORCEADD Q_RES..2
(-3275 6125);
FORCEPROP 1 LAST LOCATION R1628
J 0
(-3250 6225);
DISPLAY 0.489362 (-3250 6225);
PAINT SKYBLUE (-3250 6225);
FORCEPROP 2 LAST $SEC 1
J 0
(-3225 6350);
DISPLAY 0.680851 (-3225 6350);
PAINT MONO (-3225 6350);
DISPLAY INVISIBLE (-3225 6350);
FORCEPROP 2 LAST CDS_SEC 1
J 0
(-3225 6350);
DISPLAY 1.021277 (-3225 6350);
DISPLAY INVISIBLE (-3225 6350);
FORCEPROP 1 LASTPIN (-3275 6225) $PN 1
J 0
(-3270 6187);
DISPLAY 0.489362 (-3270 6187);
FORCEPROP 1 LASTPIN (-3275 6025) $PN 2
J 0
(-3270 6035);
DISPLAY 0.489362 (-3270 6035);
FORCEPROP 1 LAST VALUE 1K
J 0
(-3250 6175);
DISPLAY 0.489362 (-3250 6175);
PAINT SKYBLUE (-3250 6175);
FORCEPROP 1 LAST TOLERANCE 1%
J 0
(-3250 6125);
DISPLAY 0.489362 (-3250 6125);
PAINT SKYBLUE (-3250 6125);
FORCEPROP 2 LAST CDS_LIB pure_quanta
J 0
(-3275 6125);
DISPLAY INVISIBLE (-3275 6125);
FORCEPROP 1 LAST WATTAGE 1/16W
J 0
(-3250 6075);
DISPLAY 0.489362 (-3250 6075);
PAINT SKYBLUE (-3250 6075);
DISPLAY INVISIBLE (-3250 6075);
FORCEPROP 1 LAST MATERIAL CHIP
J 0
(-3250 6025);
DISPLAY 0.489362 (-3250 6025);
PAINT SKYBLUE (-3250 6025);
DISPLAY INVISIBLE (-3250 6025);
FORCEPROP 1 LAST PACK_TYPE 0402LF
J 0
(-3250 5975);
DISPLAY 0.489362 (-3250 5975);
PAINT SKYBLUE (-3250 5975);
DISPLAY INVISIBLE (-3250 5975);
FORCEPROP 1 LAST PATH I117
J 0
(-3225 6300);
DISPLAY 0.978723 (-3225 6300);
PAINT WHITE (-3225 6300);
DISPLAY INVISIBLE (-3225 6300);
FORCEPROP 1 LAST PART_NUMBER CS21002FB06
J 0
(-3235 6000);
DISPLAY 0.617021 (-3235 6000);
PAINT SKYBLUE (-3235 6000);
DISPLAY INVISIBLE (-3235 6000);
FORCEADD Q_RES..2
(-3150 6125);
FORCEPROP 1 LAST LOCATION R1630
J 0
(-3125 6225);
DISPLAY 0.489362 (-3125 6225);
PAINT SKYBLUE (-3125 6225);
FORCEPROP 2 LAST $SEC 1
J 0
(-3100 6350);
DISPLAY 0.680851 (-3100 6350);
PAINT MONO (-3100 6350);
DISPLAY INVISIBLE (-3100 6350);
FORCEPROP 2 LAST CDS_SEC 1
J 0
(-3100 6350);
DISPLAY 1.021277 (-3100 6350);
DISPLAY INVISIBLE (-3100 6350);
FORCEPROP 1 LASTPIN (-3150 6225) $PN 1
J 0
(-3145 6187);
DISPLAY 0.489362 (-3145 6187);
FORCEPROP 1 LASTPIN (-3150 6025) $PN 2
J 0
(-3145 6035);
DISPLAY 0.489362 (-3145 6035);
FORCEPROP 1 LAST VALUE 1K
J 0
(-3125 6175);
DISPLAY 0.489362 (-3125 6175);
PAINT SKYBLUE (-3125 6175);
FORCEPROP 1 LAST TOLERANCE 1%
J 0
(-3125 6125);
DISPLAY 0.489362 (-3125 6125);
PAINT SKYBLUE (-3125 6125);
FORCEPROP 2 LAST CDS_LIB pure_quanta
J 0
(-3150 6125);
DISPLAY INVISIBLE (-3150 6125);
FORCEPROP 1 LAST WATTAGE 1/16W
J 0
(-3125 6075);
DISPLAY 0.489362 (-3125 6075);
PAINT SKYBLUE (-3125 6075);
DISPLAY INVISIBLE (-3125 6075);
FORCEPROP 1 LAST MATERIAL CHIP
J 0
(-3125 6025);
DISPLAY 0.489362 (-3125 6025);
PAINT SKYBLUE (-3125 6025);
DISPLAY INVISIBLE (-3125 6025);
FORCEPROP 1 LAST PACK_TYPE 0402LF
J 0
(-3125 5975);
DISPLAY 0.489362 (-3125 5975);
PAINT SKYBLUE (-3125 5975);
DISPLAY INVISIBLE (-3125 5975);
FORCEPROP 1 LAST PATH I118
J 0
(-3100 6300);
DISPLAY 0.978723 (-3100 6300);
PAINT WHITE (-3100 6300);
DISPLAY INVISIBLE (-3100 6300);
FORCEPROP 1 LAST PART_NUMBER CS21002FB06
J 0
(-3110 6000);
DISPLAY 0.617021 (-3110 6000);
PAINT SKYBLUE (-3110 6000);
DISPLAY INVISIBLE (-3110 6000);
FORCEADD UNIVERSAL_POWER..1
(-3650 6400);
FORCEPROP 3 LASTPIN (-3650 6350) SIG_NAME PVDD18_S5_P0\g
J 0
(-3640 6360);
DISPLAY 0.659574 (-3640 6360);
PAINT MONO (-3640 6360);
DISPLAY INVISIBLE (-3640 6360);
FORCEPROP 1 LAST HDL_POWER PVDD18_S5_P0
J 1
(-3550 6450);
DISPLAY 0.489362 (-3550 6450);
PAINT GREEN (-3550 6450);
FORCEPROP 2 LAST CDS_LIB pure_quanta_power
J 0
(-3650 6400);
DISPLAY INVISIBLE (-3650 6400);
FORCEPROP 1 LAST PATH I119
J 0
(-3600 6425);
DISPLAY 0.872340 (-3600 6425);
PAINT AQUA (-3600 6425);
DISPLAY INVISIBLE (-3600 6425);
FORCEADD UNIVERSAL_POWER..1
(-2725 4850);
FORCEPROP 3 LASTPIN (-2725 4800) SIG_NAME PVDD18_S5_P0\g
J 0
(-2715 4810);
DISPLAY 0.659574 (-2715 4810);
PAINT MONO (-2715 4810);
DISPLAY INVISIBLE (-2715 4810);
FORCEPROP 1 LAST HDL_POWER PVDD18_S5_P0
J 1
(-2725 4900);
DISPLAY 0.489362 (-2725 4900);
PAINT GREEN (-2725 4900);
FORCEPROP 2 LAST CDS_LIB pure_quanta_power
J 0
(-2725 4850);
PAINT MONO (-2725 4850);
DISPLAY INVISIBLE (-2725 4850);
FORCEPROP 1 LAST PATH I12
J 0
(-2675 4875);
DISPLAY 0.872340 (-2675 4875);
PAINT AQUA (-2675 4875);
DISPLAY INVISIBLE (-2675 4875);
FORCEADD GND..1
(-2350 5100);
FORCEPROP 3 LASTPIN (-2350 5150) SIG_NAME GND\g
J 0
(-2340 5160);
DISPLAY 0.659574 (-2340 5160);
PAINT MONO (-2340 5160);
DISPLAY INVISIBLE (-2340 5160);
FORCEPROP 2 LAST CDS_LIB pure_quanta_power
J 0
(-2350 5100);
DISPLAY INVISIBLE (-2350 5100);
FORCEPROP 1 LAST SIZE 1B
J 0
(-2275 5050);
DISPLAY 0.872340 (-2275 5050);
PAINT GREEN (-2275 5050);
DISPLAY INVISIBLE (-2275 5050);
FORCEPROP 1 LAST HDL_POWER GND
J 0
(-2350 5250);
DISPLAY 0.872340 (-2350 5250);
PAINT GREEN (-2350 5250);
DISPLAY INVISIBLE (-2350 5250);
FORCEPROP 1 LAST PATH I120
J 0
(-2275 5100);
DISPLAY 0.872340 (-2275 5100);
PAINT AQUA (-2275 5100);
DISPLAY INVISIBLE (-2275 5100);
FORCEADD GND..1
(-2125 5100);
FORCEPROP 3 LASTPIN (-2125 5150) SIG_NAME GND\g
J 0
(-2115 5160);
DISPLAY 0.659574 (-2115 5160);
PAINT MONO (-2115 5160);
DISPLAY INVISIBLE (-2115 5160);
FORCEPROP 1 LAST SIZE 1B
J 0
(-2050 5050);
DISPLAY 0.872340 (-2050 5050);
PAINT GREEN (-2050 5050);
DISPLAY INVISIBLE (-2050 5050);
FORCEPROP 2 LAST CDS_LIB pure_quanta_power
J 0
(-2125 5100);
DISPLAY INVISIBLE (-2125 5100);
FORCEPROP 1 LAST HDL_POWER GND
J 0
(-2125 5250);
DISPLAY 0.872340 (-2125 5250);
PAINT GREEN (-2125 5250);
DISPLAY INVISIBLE (-2125 5250);
FORCEPROP 1 LAST PATH I121
J 0
(-2050 5100);
DISPLAY 0.872340 (-2050 5100);
PAINT AQUA (-2050 5100);
DISPLAY INVISIBLE (-2050 5100);
FORCEADD Q_CAP..1
(-2125 5325);
FORCEPROP 1 LAST LOCATION C551
J 0
(-2075 5425);
DISPLAY 0.489362 (-2075 5425);
PAINT SKYBLUE (-2075 5425);
FORCEPROP 2 LAST $SEC 1
J 0
(-2075 5525);
DISPLAY 0.680851 (-2075 5525);
PAINT MONO (-2075 5525);
DISPLAY INVISIBLE (-2075 5525);
FORCEPROP 2 LAST CDS_SEC 1
J 0
(-2075 5525);
DISPLAY 1.021277 (-2075 5525);
DISPLAY INVISIBLE (-2075 5525);
FORCEPROP 1 LASTPIN (-2125 5425) $PN 1
J 0
(-2115 5405);
DISPLAY 0.489362 (-2115 5405);
FORCEPROP 1 LASTPIN (-2125 5225) $PN 2
J 0
(-2115 5205);
DISPLAY 0.489362 (-2115 5205);
FORCEPROP 1 LAST VALUE 0.01UF
J 0
(-2075 5375);
DISPLAY 0.489362 (-2075 5375);
PAINT SKYBLUE (-2075 5375);
FORCEPROP 1 LAST VOLTAGE 50V
J 0
(-2075 5325);
DISPLAY 0.489362 (-2075 5325);
PAINT SKYBLUE (-2075 5325);
FORCEPROP 1 LAST TOLERANCE 10%
J 0
(-2075 5275);
DISPLAY 0.489362 (-2075 5275);
PAINT SKYBLUE (-2075 5275);
FORCEPROP 1 LAST PACK_TYPE C0402
J 0
(-2075 5175);
DISPLAY 0.489362 (-2075 5175);
PAINT SKYBLUE (-2075 5175);
FORCEPROP 1 LAST MATERIAL X7R
J 0
(-2075 5225);
DISPLAY 0.489362 (-2075 5225);
PAINT SKYBLUE (-2075 5225);
FORCEPROP 2 LAST CDS_LIB pure_quanta
J 0
(-2125 5325);
DISPLAY INVISIBLE (-2125 5325);
FORCEPROP 2 LAST SIGNAL_MODEL DEFAULT_CAPACITOR_10000PF_2_1
J 0
(-2075 5525);
DISPLAY 0.808511 (-2075 5525);
PAINT MONO (-2075 5525);
DISPLAY INVISIBLE (-2075 5525);
FORCEPROP 1 LAST PATH I123
J 0
(-2075 5475);
DISPLAY 0.978723 (-2075 5475);
PAINT WHITE (-2075 5475);
DISPLAY INVISIBLE (-2075 5475);
FORCEPROP 1 LAST PART_NUMBER CH31006KB18
R 1
J 0
(-2175 5075);
DISPLAY 0.617021 (-2175 5075);
PAINT SKYBLUE (-2175 5075);
DISPLAY INVISIBLE (-2175 5075);
FORCEADD OFFPAGE..2
(-1625 5600);
FORCEPROP 2 LAST $XR0 172 
J 0
(-1436 5600);
DISPLAY 0.638298 (-1436 5600);
PAINT MONO (-1436 5600);
FORCEPROP 2 LAST CDS_LIB standard
J 0
(-1625 5600);
DISPLAY INVISIBLE (-1625 5600);
FORCEPROP 1 LAST OFFPAGE TRUE
J 0
(-1300 5475);
DISPLAY 0.872340 (-1300 5475);
PAINT GREEN (-1300 5475);
DISPLAY INVISIBLE (-1300 5475);
FORCEPROP 1 LAST COMMENT_BODY TRUE
J 0
(-1670 5505);
DISPLAY 0.872340 (-1670 5505);
PAINT GREEN (-1670 5505);
DISPLAY INVISIBLE (-1670 5505);
FORCEPROP 2 LAST PATH I124
J 0
(-1425 5650);
DISPLAY 0.680851 (-1425 5650);
DISPLAY INVISIBLE (-1425 5650);
FORCEADD OFFPAGE..1
R 2
(-1650 5700);
FORCEPROP 2 LAST $XR0 81 
J 0
(-1464 5700);
DISPLAY 0.638298 (-1464 5700);
PAINT MONO (-1464 5700);
FORCEPROP 2 LAST CDS_LIB standard
J 0
(-1650 5700);
PAINT MONO (-1650 5700);
DISPLAY INVISIBLE (-1650 5700);
FORCEPROP 1 LAST OFFPAGE TRUE
J 2
(-1975 5575);
DISPLAY 0.872340 (-1975 5575);
PAINT GREEN (-1975 5575);
DISPLAY INVISIBLE (-1975 5575);
FORCEPROP 1 LAST COMMENT_BODY TRUE
J 2
(-1775 5600);
DISPLAY 0.872340 (-1775 5600);
PAINT GREEN (-1775 5600);
DISPLAY INVISIBLE (-1775 5600);
FORCEPROP 2 LAST PATH I125
J 0
(-1450 5750);
DISPLAY 0.680851 (-1450 5750);
DISPLAY INVISIBLE (-1450 5750);
FORCEADD OFFPAGE..2
(-1625 5550);
FORCEPROP 2 LAST $XR0 81 
J 0
(-1436 5550);
DISPLAY 0.638298 (-1436 5550);
PAINT MONO (-1436 5550);
FORCEPROP 2 LAST CDS_LIB standard
J 0
(-1625 5550);
DISPLAY INVISIBLE (-1625 5550);
FORCEPROP 1 LAST OFFPAGE TRUE
J 0
(-1300 5425);
DISPLAY 0.872340 (-1300 5425);
PAINT GREEN (-1300 5425);
DISPLAY INVISIBLE (-1300 5425);
FORCEPROP 1 LAST COMMENT_BODY TRUE
J 0
(-1670 5455);
DISPLAY 0.872340 (-1670 5455);
PAINT GREEN (-1670 5455);
DISPLAY INVISIBLE (-1670 5455);
FORCEPROP 2 LAST PATH I126
J 0
(-1425 5600);
DISPLAY 0.680851 (-1425 5600);
DISPLAY INVISIBLE (-1425 5600);
FORCEADD OFFPAGE..1
R 2
(-1650 5750);
FORCEPROP 2 LAST $XR0 81 
J 0
(-1464 5750);
DISPLAY 0.638298 (-1464 5750);
PAINT MONO (-1464 5750);
FORCEPROP 2 LAST CDS_LIB standard
J 0
(-1650 5750);
PAINT MONO (-1650 5750);
DISPLAY INVISIBLE (-1650 5750);
FORCEPROP 1 LAST OFFPAGE TRUE
J 2
(-1975 5625);
DISPLAY 0.872340 (-1975 5625);
PAINT GREEN (-1975 5625);
DISPLAY INVISIBLE (-1975 5625);
FORCEPROP 1 LAST COMMENT_BODY TRUE
J 2
(-1775 5650);
DISPLAY 0.872340 (-1775 5650);
PAINT GREEN (-1775 5650);
DISPLAY INVISIBLE (-1775 5650);
FORCEPROP 2 LAST PATH I127
J 0
(-1450 5800);
DISPLAY 0.680851 (-1450 5800);
DISPLAY INVISIBLE (-1450 5800);
FORCEADD OFFPAGE..2
(-1650 5850);
FORCEPROP 2 LAST $XR0 172 
J 0
(-1461 5850);
DISPLAY 0.638298 (-1461 5850);
PAINT MONO (-1461 5850);
FORCEPROP 2 LAST CDS_LIB standard
J 0
(-1650 5850);
DISPLAY INVISIBLE (-1650 5850);
FORCEPROP 1 LAST OFFPAGE TRUE
J 0
(-1325 5725);
DISPLAY 0.872340 (-1325 5725);
PAINT GREEN (-1325 5725);
DISPLAY INVISIBLE (-1325 5725);
FORCEPROP 1 LAST COMMENT_BODY TRUE
J 0
(-1695 5755);
DISPLAY 0.872340 (-1695 5755);
PAINT GREEN (-1695 5755);
DISPLAY INVISIBLE (-1695 5755);
FORCEPROP 2 LAST PATH I128
J 0
(-1450 5900);
DISPLAY 0.680851 (-1450 5900);
DISPLAY INVISIBLE (-1450 5900);
FORCEADD OFFPAGE..1
R 2
(-1650 5800);
FORCEPROP 2 LAST $XR0 172 
J 0
(-1464 5800);
DISPLAY 0.638298 (-1464 5800);
PAINT MONO (-1464 5800);
FORCEPROP 2 LAST CDS_LIB standard
J 2
(-1650 5800);
DISPLAY INVISIBLE (-1650 5800);
FORCEPROP 1 LAST OFFPAGE TRUE
J 2
(-1975 5675);
DISPLAY 0.872340 (-1975 5675);
PAINT GREEN (-1975 5675);
DISPLAY INVISIBLE (-1975 5675);
FORCEPROP 1 LAST COMMENT_BODY TRUE
J 2
(-1775 5700);
DISPLAY 0.872340 (-1775 5700);
PAINT GREEN (-1775 5700);
DISPLAY INVISIBLE (-1775 5700);
FORCEPROP 2 LAST PATH I129
J 0
(-1450 5850);
DISPLAY 0.680851 (-1450 5850);
DISPLAY INVISIBLE (-1450 5850);
FORCEADD OFFPAGE..2
(-1650 5950);
FORCEPROP 2 LAST $XR0 172 
J 0
(-1461 5950);
DISPLAY 0.638298 (-1461 5950);
PAINT MONO (-1461 5950);
FORCEPROP 2 LAST CDS_LIB standard
J 0
(-1650 5950);
DISPLAY INVISIBLE (-1650 5950);
FORCEPROP 1 LAST OFFPAGE TRUE
J 0
(-1325 5825);
DISPLAY 0.872340 (-1325 5825);
PAINT GREEN (-1325 5825);
DISPLAY INVISIBLE (-1325 5825);
FORCEPROP 1 LAST COMMENT_BODY TRUE
J 0
(-1695 5855);
DISPLAY 0.872340 (-1695 5855);
PAINT GREEN (-1695 5855);
DISPLAY INVISIBLE (-1695 5855);
FORCEPROP 2 LAST PATH I130
J 0
(-1450 6000);
DISPLAY 0.680851 (-1450 6000);
DISPLAY INVISIBLE (-1450 6000);
FORCEADD OFFPAGE..2
(-1650 5900);
FORCEPROP 2 LAST $XR0 172 
J 0
(-1461 5900);
DISPLAY 0.638298 (-1461 5900);
PAINT MONO (-1461 5900);
FORCEPROP 2 LAST CDS_LIB standard
J 0
(-1650 5900);
DISPLAY INVISIBLE (-1650 5900);
FORCEPROP 1 LAST OFFPAGE TRUE
J 0
(-1325 5775);
DISPLAY 0.872340 (-1325 5775);
PAINT GREEN (-1325 5775);
DISPLAY INVISIBLE (-1325 5775);
FORCEPROP 1 LAST COMMENT_BODY TRUE
J 0
(-1695 5805);
DISPLAY 0.872340 (-1695 5805);
PAINT GREEN (-1695 5805);
DISPLAY INVISIBLE (-1695 5805);
FORCEPROP 2 LAST PATH I131
J 0
(-1450 5950);
DISPLAY 0.680851 (-1450 5950);
DISPLAY INVISIBLE (-1450 5950);
FORCEADD Q_RES..1
(-3975 5950);
FORCEPROP 1 LAST LOCATION R1352
J 0
(-4175 5950);
DISPLAY 0.489362 (-4175 5950);
PAINT SKYBLUE (-4175 5950);
FORCEPROP 0 LAST $SEC 1
J 0
(-4100 6000);
DISPLAY 0.680851 (-4100 6000);
PAINT MONO (-4100 6000);
DISPLAY INVISIBLE (-4100 6000);
FORCEPROP 0 LAST CDS_SEC 1
J 0
(-4100 6000);
DISPLAY 0.680851 (-4100 6000);
DISPLAY INVISIBLE (-4100 6000);
FORCEPROP 1 LASTPIN (-4075 5950) $PN 1
J 0
(-4063 5962);
DISPLAY 0.489362 (-4063 5962);
PAINT MONO (-4063 5962);
FORCEPROP 1 LASTPIN (-3875 5950) $PN 2
J 0
(-3913 5962);
DISPLAY 0.489362 (-3913 5962);
PAINT MONO (-3913 5962);
FORCEPROP 1 LAST VALUE 0
J 2
(-3825 5950);
DISPLAY 0.489362 (-3825 5950);
PAINT SKYBLUE (-3825 5950);
FORCEPROP 2 LAST CDS_LIB pure_quanta
J 0
(-3975 5950);
DISPLAY INVISIBLE (-3975 5950);
FORCEPROP 1 LAST WATTAGE 1/16W
J 2
(-4000 5800);
DISPLAY 0.978723 (-4000 5800);
PAINT SKYBLUE (-4000 5800);
DISPLAY INVISIBLE (-4000 5800);
FORCEPROP 1 LAST MATERIAL CHIP
J 0
(-3750 5950);
DISPLAY 0.617021 (-3750 5950);
PAINT SKYBLUE (-3750 5950);
DISPLAY INVISIBLE (-3750 5950);
FORCEPROP 1 LAST TOLERANCE 5%
J 0
(-3975 5850);
DISPLAY 0.978723 (-3975 5850);
PAINT SKYBLUE (-3975 5850);
DISPLAY INVISIBLE (-3975 5850);
FORCEPROP 1 LAST PACK_TYPE 0402LF
J 0
(-3725 5800);
DISPLAY 0.978723 (-3725 5800);
PAINT SKYBLUE (-3725 5800);
DISPLAY INVISIBLE (-3725 5800);
FORCEPROP 1 LAST PATH I132
J 0
(-4025 6100);
DISPLAY 0.978723 (-4025 6100);
PAINT WHITE (-4025 6100);
DISPLAY INVISIBLE (-4025 6100);
FORCEPROP 1 LAST PART_NUMBER CS00002JB13
J 0
(-4025 6050);
DISPLAY 0.978723 (-4025 6050);
PAINT SKYBLUE (-4025 6050);
DISPLAY INVISIBLE (-4025 6050);
FORCEADD Q_RES..1
(-3975 5900);
FORCEPROP 1 LAST LOCATION R1353
J 0
(-4175 5900);
DISPLAY 0.489362 (-4175 5900);
PAINT SKYBLUE (-4175 5900);
FORCEPROP 0 LAST $SEC 1
J 0
(-4100 5950);
DISPLAY 0.680851 (-4100 5950);
PAINT MONO (-4100 5950);
DISPLAY INVISIBLE (-4100 5950);
FORCEPROP 0 LAST CDS_SEC 1
J 0
(-4100 5950);
DISPLAY 0.680851 (-4100 5950);
DISPLAY INVISIBLE (-4100 5950);
FORCEPROP 1 LASTPIN (-4075 5900) $PN 1
J 0
(-4063 5912);
DISPLAY 0.489362 (-4063 5912);
PAINT MONO (-4063 5912);
FORCEPROP 1 LASTPIN (-3875 5900) $PN 2
J 0
(-3913 5912);
DISPLAY 0.489362 (-3913 5912);
PAINT MONO (-3913 5912);
FORCEPROP 1 LAST VALUE 0
J 2
(-3825 5900);
DISPLAY 0.489362 (-3825 5900);
PAINT SKYBLUE (-3825 5900);
FORCEPROP 2 LAST CDS_LIB pure_quanta
J 0
(-3975 5900);
DISPLAY INVISIBLE (-3975 5900);
FORCEPROP 1 LAST WATTAGE 1/16W
J 2
(-4000 5750);
DISPLAY 0.978723 (-4000 5750);
PAINT SKYBLUE (-4000 5750);
DISPLAY INVISIBLE (-4000 5750);
FORCEPROP 1 LAST MATERIAL CHIP
J 0
(-3750 5900);
DISPLAY 0.617021 (-3750 5900);
PAINT SKYBLUE (-3750 5900);
DISPLAY INVISIBLE (-3750 5900);
FORCEPROP 1 LAST TOLERANCE 5%
J 0
(-3975 5800);
DISPLAY 0.978723 (-3975 5800);
PAINT SKYBLUE (-3975 5800);
DISPLAY INVISIBLE (-3975 5800);
FORCEPROP 1 LAST PACK_TYPE 0402LF
J 0
(-3725 5750);
DISPLAY 0.978723 (-3725 5750);
PAINT SKYBLUE (-3725 5750);
DISPLAY INVISIBLE (-3725 5750);
FORCEPROP 1 LAST PATH I133
J 0
(-4025 6050);
DISPLAY 0.978723 (-4025 6050);
PAINT WHITE (-4025 6050);
DISPLAY INVISIBLE (-4025 6050);
FORCEPROP 1 LAST PART_NUMBER CS00002JB13
J 0
(-4025 6000);
DISPLAY 0.978723 (-4025 6000);
PAINT SKYBLUE (-4025 6000);
DISPLAY INVISIBLE (-4025 6000);
FORCEADD Q_CAP..1
(-2350 5325);
FORCEPROP 1 LAST LOCATION C87
J 0
(-2300 5425);
DISPLAY 0.489362 (-2300 5425);
PAINT SKYBLUE (-2300 5425);
FORCEPROP 0 LAST $SEC 1
J 0
(-2300 5450);
DISPLAY 0.680851 (-2300 5450);
PAINT MONO (-2300 5450);
DISPLAY INVISIBLE (-2300 5450);
FORCEPROP 0 LAST CDS_SEC 1
J 0
(-2300 5450);
DISPLAY 0.680851 (-2300 5450);
DISPLAY INVISIBLE (-2300 5450);
FORCEPROP 1 LASTPIN (-2350 5425) $PN 1
J 0
(-2340 5405);
DISPLAY 0.489362 (-2340 5405);
PAINT MONO (-2340 5405);
FORCEPROP 1 LASTPIN (-2350 5225) $PN 2
J 0
(-2340 5205);
DISPLAY 0.489362 (-2340 5205);
PAINT MONO (-2340 5205);
FORCEPROP 1 LAST VALUE 0.001UF
J 0
(-2300 5375);
DISPLAY 0.489362 (-2300 5375);
PAINT SKYBLUE (-2300 5375);
FORCEPROP 1 LAST TOLERANCE 10%
J 0
(-2300 5275);
DISPLAY 0.489362 (-2300 5275);
PAINT SKYBLUE (-2300 5275);
FORCEPROP 1 LAST PACK_TYPE C0402
J 0
(-2300 5175);
DISPLAY 0.489362 (-2300 5175);
PAINT SKYBLUE (-2300 5175);
FORCEPROP 1 LAST VOLTAGE 50V
J 0
(-2300 5325);
DISPLAY 0.489362 (-2300 5325);
PAINT SKYBLUE (-2300 5325);
FORCEPROP 1 LAST MATERIAL X7R
J 0
(-2300 5225);
DISPLAY 0.489362 (-2300 5225);
PAINT SKYBLUE (-2300 5225);
FORCEPROP 2 LAST CDS_LIB pure_quanta
J 0
(-2350 5325);
DISPLAY INVISIBLE (-2350 5325);
FORCEPROP 1 LAST PATH I134
J 0
(-2300 5475);
DISPLAY 0.978723 (-2300 5475);
PAINT WHITE (-2300 5475);
DISPLAY INVISIBLE (-2300 5475);
FORCEPROP 1 LAST PART_NUMBER CH30106KB19
J 0
(-2300 5225);
DISPLAY 0.808511 (-2300 5225);
PAINT SKYBLUE (-2300 5225);
DISPLAY INVISIBLE (-2300 5225);
FORCEADD Q_CAP..1
(-2575 5325);
FORCEPROP 1 LAST LOCATION C605
J 0
(-2525 5425);
DISPLAY 0.489362 (-2525 5425);
PAINT SKYBLUE (-2525 5425);
FORCEPROP 0 LAST $SEC 1
J 0
(-2525 5450);
DISPLAY 0.680851 (-2525 5450);
PAINT MONO (-2525 5450);
DISPLAY INVISIBLE (-2525 5450);
FORCEPROP 0 LAST CDS_SEC 1
J 0
(-2525 5450);
DISPLAY 0.680851 (-2525 5450);
DISPLAY INVISIBLE (-2525 5450);
FORCEPROP 1 LASTPIN (-2575 5425) $PN 1
J 0
(-2565 5405);
DISPLAY 0.489362 (-2565 5405);
PAINT MONO (-2565 5405);
FORCEPROP 1 LASTPIN (-2575 5225) $PN 2
J 0
(-2565 5205);
DISPLAY 0.489362 (-2565 5205);
PAINT MONO (-2565 5205);
FORCEPROP 1 LAST VALUE 0.001UF
J 0
(-2525 5375);
DISPLAY 0.489362 (-2525 5375);
PAINT SKYBLUE (-2525 5375);
FORCEPROP 1 LAST PACK_TYPE C0402
J 0
(-2525 5175);
DISPLAY 0.489362 (-2525 5175);
PAINT SKYBLUE (-2525 5175);
FORCEPROP 1 LAST VOLTAGE 50V
J 0
(-2525 5325);
DISPLAY 0.489362 (-2525 5325);
PAINT SKYBLUE (-2525 5325);
FORCEPROP 1 LAST TOLERANCE 10%
J 0
(-2525 5275);
DISPLAY 0.489362 (-2525 5275);
PAINT SKYBLUE (-2525 5275);
FORCEPROP 1 LAST MATERIAL X7R
J 0
(-2525 5225);
DISPLAY 0.489362 (-2525 5225);
PAINT SKYBLUE (-2525 5225);
FORCEPROP 2 LAST CDS_LIB pure_quanta
J 0
(-2575 5325);
DISPLAY INVISIBLE (-2575 5325);
FORCEPROP 1 LAST PATH I137
J 0
(-2525 5475);
DISPLAY 0.978723 (-2525 5475);
PAINT WHITE (-2525 5475);
DISPLAY INVISIBLE (-2525 5475);
FORCEPROP 1 LAST PART_NUMBER CH30106KB19
J 0
(-2525 5225);
DISPLAY 0.808511 (-2525 5225);
PAINT SKYBLUE (-2525 5225);
DISPLAY INVISIBLE (-2525 5225);
FORCEADD GND..1
(-2575 5100);
FORCEPROP 3 LASTPIN (-2575 5150) SIG_NAME GND\g
J 0
(-2565 5160);
DISPLAY 0.659574 (-2565 5160);
PAINT MONO (-2565 5160);
DISPLAY INVISIBLE (-2565 5160);
FORCEPROP 2 LAST CDS_LIB pure_quanta_power
J 0
(-2575 5100);
DISPLAY INVISIBLE (-2575 5100);
FORCEPROP 1 LAST SIZE 1B
J 0
(-2500 5050);
DISPLAY 0.872340 (-2500 5050);
PAINT GREEN (-2500 5050);
DISPLAY INVISIBLE (-2500 5050);
FORCEPROP 1 LAST HDL_POWER GND
J 0
(-2575 5250);
DISPLAY 0.872340 (-2575 5250);
PAINT GREEN (-2575 5250);
DISPLAY INVISIBLE (-2575 5250);
FORCEPROP 1 LAST PATH I138
J 0
(-2500 5100);
DISPLAY 0.872340 (-2500 5100);
PAINT AQUA (-2500 5100);
DISPLAY INVISIBLE (-2500 5100);
FORCEADD Q_CAP..1
(-2800 5325);
FORCEPROP 1 LAST LOCATION C604
J 0
(-2750 5425);
DISPLAY 0.489362 (-2750 5425);
PAINT SKYBLUE (-2750 5425);
FORCEPROP 0 LAST $SEC 1
J 0
(-2750 5475);
DISPLAY 0.680851 (-2750 5475);
PAINT MONO (-2750 5475);
DISPLAY INVISIBLE (-2750 5475);
FORCEPROP 0 LAST CDS_SEC 1
J 0
(-2750 5475);
DISPLAY 0.680851 (-2750 5475);
DISPLAY INVISIBLE (-2750 5475);
FORCEPROP 1 LASTPIN (-2800 5425) $PN 1
J 0
(-2790 5405);
DISPLAY 0.489362 (-2790 5405);
PAINT MONO (-2790 5405);
FORCEPROP 1 LASTPIN (-2800 5225) $PN 2
J 0
(-2790 5205);
DISPLAY 0.489362 (-2790 5205);
PAINT MONO (-2790 5205);
FORCEPROP 1 LAST VALUE 0.001UF
J 0
(-2750 5375);
DISPLAY 0.489362 (-2750 5375);
PAINT SKYBLUE (-2750 5375);
FORCEPROP 1 LAST PACK_TYPE C0402
J 0
(-2750 5175);
DISPLAY 0.489362 (-2750 5175);
PAINT SKYBLUE (-2750 5175);
FORCEPROP 1 LAST VOLTAGE 50V
J 0
(-2750 5325);
DISPLAY 0.489362 (-2750 5325);
PAINT SKYBLUE (-2750 5325);
FORCEPROP 1 LAST TOLERANCE 10%
J 0
(-2750 5275);
DISPLAY 0.489362 (-2750 5275);
PAINT SKYBLUE (-2750 5275);
FORCEPROP 1 LAST MATERIAL X7R
J 0
(-2750 5225);
DISPLAY 0.489362 (-2750 5225);
PAINT SKYBLUE (-2750 5225);
FORCEPROP 2 LAST CDS_LIB pure_quanta
J 0
(-2800 5325);
DISPLAY INVISIBLE (-2800 5325);
FORCEPROP 1 LAST PATH I140
J 0
(-2750 5475);
DISPLAY 0.978723 (-2750 5475);
PAINT WHITE (-2750 5475);
DISPLAY INVISIBLE (-2750 5475);
FORCEPROP 1 LAST PART_NUMBER CH30106KB19
J 0
(-2750 5225);
DISPLAY 0.808511 (-2750 5225);
PAINT SKYBLUE (-2750 5225);
DISPLAY INVISIBLE (-2750 5225);
FORCEADD GND..1
(-2800 5100);
FORCEPROP 3 LASTPIN (-2800 5150) SIG_NAME GND\g
J 0
(-2790 5160);
DISPLAY 0.659574 (-2790 5160);
PAINT MONO (-2790 5160);
DISPLAY INVISIBLE (-2790 5160);
FORCEPROP 2 LAST CDS_LIB pure_quanta_power
J 0
(-2800 5100);
DISPLAY INVISIBLE (-2800 5100);
FORCEPROP 1 LAST SIZE 1B
J 0
(-2725 5050);
DISPLAY 0.872340 (-2725 5050);
PAINT GREEN (-2725 5050);
DISPLAY INVISIBLE (-2725 5050);
FORCEPROP 1 LAST HDL_POWER GND
J 0
(-2800 5250);
DISPLAY 0.872340 (-2800 5250);
PAINT GREEN (-2800 5250);
DISPLAY INVISIBLE (-2800 5250);
FORCEPROP 1 LAST PATH I141
J 0
(-2725 5100);
DISPLAY 0.872340 (-2725 5100);
PAINT AQUA (-2725 5100);
DISPLAY INVISIBLE (-2725 5100);
FORCEADD SCONN20_HSU2101L00007H..1
(-5125 5725);
FORCEPROP 1 LAST LOCATION J54
J 0
(-5219 6281);
DISPLAY 0.489362 (-5219 6281);
PAINT SKYBLUE (-5219 6281);
FORCEPROP 0 LAST $SEC 1
J 0
(-5200 6425);
DISPLAY 0.680851 (-5200 6425);
PAINT MONO (-5200 6425);
DISPLAY INVISIBLE (-5200 6425);
FORCEPROP 0 LAST CDS_SEC 1
J 0
(-5200 6425);
DISPLAY 0.680851 (-5200 6425);
DISPLAY INVISIBLE (-5200 6425);
FORCEPROP 0 LASTPIN (-5375 5950) $PN 1
J 2
(-5385 5960);
DISPLAY 0.489362 (-5385 5960);
PAINT MONO (-5385 5960);
FORCEPROP 0 LASTPIN (-4875 5950) $PN 2
J 0
(-4865 5960);
DISPLAY 0.489362 (-4865 5960);
PAINT MONO (-4865 5960);
FORCEPROP 0 LASTPIN (-5375 5900) $PN 3
J 2
(-5385 5910);
DISPLAY 0.489362 (-5385 5910);
PAINT MONO (-5385 5910);
FORCEPROP 0 LASTPIN (-4875 5900) $PN 4
J 0
(-4865 5910);
DISPLAY 0.489362 (-4865 5910);
PAINT MONO (-4865 5910);
FORCEPROP 0 LASTPIN (-5375 5850) $PN 5
J 2
(-5385 5860);
DISPLAY 0.489362 (-5385 5860);
PAINT MONO (-5385 5860);
FORCEPROP 0 LASTPIN (-4875 5850) $PN 6
J 0
(-4865 5860);
DISPLAY 0.489362 (-4865 5860);
PAINT MONO (-4865 5860);
FORCEPROP 0 LASTPIN (-5375 5800) $PN 7
J 2
(-5385 5810);
DISPLAY 0.489362 (-5385 5810);
PAINT MONO (-5385 5810);
FORCEPROP 0 LASTPIN (-4875 5800) $PN 8
J 0
(-4865 5810);
DISPLAY 0.489362 (-4865 5810);
PAINT MONO (-4865 5810);
FORCEPROP 0 LASTPIN (-5375 5750) $PN 9
J 2
(-5385 5760);
DISPLAY 0.489362 (-5385 5760);
PAINT MONO (-5385 5760);
FORCEPROP 0 LASTPIN (-4875 5750) $PN 10
J 0
(-4865 5760);
DISPLAY 0.489362 (-4865 5760);
PAINT MONO (-4865 5760);
FORCEPROP 0 LASTPIN (-5375 5700) $PN 11
J 2
(-5385 5710);
DISPLAY 0.489362 (-5385 5710);
PAINT MONO (-5385 5710);
FORCEPROP 0 LASTPIN (-4875 5700) $PN 12
J 0
(-4865 5710);
DISPLAY 0.489362 (-4865 5710);
PAINT MONO (-4865 5710);
FORCEPROP 0 LASTPIN (-5375 5650) $PN 13
J 2
(-5385 5660);
DISPLAY 0.489362 (-5385 5660);
PAINT MONO (-5385 5660);
FORCEPROP 0 LASTPIN (-4875 5650) $PN 14
J 0
(-4865 5660);
DISPLAY 0.489362 (-4865 5660);
PAINT MONO (-4865 5660);
FORCEPROP 0 LASTPIN (-5375 5600) $PN 15
J 2
(-5385 5610);
DISPLAY 0.489362 (-5385 5610);
PAINT MONO (-5385 5610);
FORCEPROP 0 LASTPIN (-4875 5600) $PN 16
J 0
(-4865 5610);
DISPLAY 0.489362 (-4865 5610);
PAINT MONO (-4865 5610);
FORCEPROP 0 LASTPIN (-5375 5550) $PN 17
J 2
(-5385 5560);
DISPLAY 0.489362 (-5385 5560);
PAINT MONO (-5385 5560);
FORCEPROP 0 LASTPIN (-4875 5550) $PN 18
J 0
(-4865 5560);
DISPLAY 0.489362 (-4865 5560);
PAINT MONO (-4865 5560);
FORCEPROP 0 LASTPIN (-5375 5500) $PN 19
J 2
(-5385 5510);
DISPLAY 0.489362 (-5385 5510);
PAINT MONO (-5385 5510);
FORCEPROP 0 LASTPIN (-4875 5500) $PN 20
J 0
(-4865 5510);
DISPLAY 0.489362 (-4865 5510);
PAINT MONO (-4865 5510);
FORCEPROP 2 LAST VALUE SCONN20_HSU2101-L0000-7H
J 0
(-5200 6325);
DISPLAY 0.489362 (-5200 6325);
PAINT SKYBLUE (-5200 6325);
FORCEPROP 1 LAST MATERIAL IO
J 0
(-5219 6007);
DISPLAY 0.489362 (-5219 6007);
PAINT SKYBLUE (-5219 6007);
FORCEPROP 2 LAST PART_TYPE SMLF
J 0
(-5200 6375);
DISPLAY 0.680851 (-5200 6375);
FORCEPROP 1 LAST CDS_LMAN_SYM_OUTLINE -100,275,100,-275
J 0
(-5125 5725);
DISPLAY 0.468085 (-5125 5725);
PAINT GREEN (-5125 5725);
DISPLAY INVISIBLE (-5125 5725);
FORCEPROP 1 LAST NEEDS_NO_SIZE TRUE
J 0
(-5125 5725);
DISPLAY 0.723404 (-5125 5725);
PAINT GREEN (-5125 5725);
DISPLAY INVISIBLE (-5125 5725);
FORCEPROP 2 LAST CDS_LIB pure_quanta
J 0
(-5125 5725);
DISPLAY INVISIBLE (-5125 5725);
FORCEPROP 1 LAST PATH I142
J 0
(-5125 5725);
DISPLAY 0.723404 (-5125 5725);
PAINT GREEN (-5125 5725);
DISPLAY INVISIBLE (-5125 5725);
FORCEPROP 1 LAST PART_NUMBER DFHD20MS153
J 0
(-5219 6134);
DISPLAY 0.489362 (-5219 6134);
PAINT SKYBLUE (-5219 6134);
DISPLAY INVISIBLE (-5219 6134);
FORCEADD GND..1
(-5475 5350);
FORCEPROP 3 LASTPIN (-5475 5400) SIG_NAME GND\g
J 0
(-5465 5410);
DISPLAY 0.659574 (-5465 5410);
PAINT MONO (-5465 5410);
DISPLAY INVISIBLE (-5465 5410);
FORCEPROP 1 LAST SIZE 1B
J 0
(-5400 5300);
DISPLAY 0.872340 (-5400 5300);
PAINT GREEN (-5400 5300);
DISPLAY INVISIBLE (-5400 5300);
FORCEPROP 2 LAST CDS_LIB pure_quanta_power
J 0
(-5475 5350);
DISPLAY INVISIBLE (-5475 5350);
FORCEPROP 1 LAST HDL_POWER GND
J 0
(-5475 5500);
DISPLAY 0.872340 (-5475 5500);
PAINT GREEN (-5475 5500);
DISPLAY INVISIBLE (-5475 5500);
FORCEPROP 1 LAST PATH I143
J 0
(-5400 5350);
DISPLAY 0.872340 (-5400 5350);
PAINT AQUA (-5400 5350);
DISPLAY INVISIBLE (-5400 5350);
FORCEADD UNIVERSAL_POWER..1
(-5600 6200);
FORCEPROP 3 LASTPIN (-5600 6150) SIG_NAME PVDD18_S5_P0\g
J 0
(-5590 6160);
DISPLAY 0.659574 (-5590 6160);
PAINT MONO (-5590 6160);
DISPLAY INVISIBLE (-5590 6160);
FORCEPROP 1 LAST HDL_POWER PVDD18_S5_P0
J 1
(-5575 6250);
DISPLAY 0.489362 (-5575 6250);
PAINT GREEN (-5575 6250);
FORCEPROP 2 LAST CDS_LIB pure_quanta_power
J 0
(-5600 6200);
DISPLAY INVISIBLE (-5600 6200);
FORCEPROP 1 LAST PATH I144
J 0
(-5550 6225);
DISPLAY 0.872340 (-5550 6225);
PAINT AQUA (-5550 6225);
DISPLAY INVISIBLE (-5550 6225);
FORCEADD UNIVERSAL_POWER..1
(-6050 6450);
FORCEPROP 3 LASTPIN (-6050 6400) SIG_NAME PVDD18_S5_P0\g
J 0
(-6040 6410);
DISPLAY 0.659574 (-6040 6410);
PAINT MONO (-6040 6410);
DISPLAY INVISIBLE (-6040 6410);
FORCEPROP 1 LAST HDL_POWER PVDD18_S5_P0
J 1
(-6025 6500);
DISPLAY 0.489362 (-6025 6500);
PAINT GREEN (-6025 6500);
FORCEPROP 2 LAST CDS_LIB pure_quanta_power
J 0
(-6050 6450);
DISPLAY INVISIBLE (-6050 6450);
FORCEPROP 1 LAST PATH I145
J 0
(-6000 6475);
DISPLAY 0.872340 (-6000 6475);
PAINT AQUA (-6000 6475);
DISPLAY INVISIBLE (-6000 6475);
FORCEADD Q_RES..2
(-6050 6250);
FORCEPROP 1 LAST LOCATION R1621
J 0
(-6000 6400);
DISPLAY 0.489362 (-6000 6400);
PAINT SKYBLUE (-6000 6400);
FORCEPROP 2 LAST $SEC 1
J 0
(-6000 6475);
DISPLAY 0.680851 (-6000 6475);
PAINT MONO (-6000 6475);
DISPLAY INVISIBLE (-6000 6475);
FORCEPROP 2 LAST CDS_SEC 1
J 0
(-6000 6475);
DISPLAY 1.021277 (-6000 6475);
DISPLAY INVISIBLE (-6000 6475);
FORCEPROP 1 LASTPIN (-6050 6350) $PN 1
J 0
(-6045 6312);
DISPLAY 0.489362 (-6045 6312);
FORCEPROP 1 LASTPIN (-6050 6150) $PN 2
J 0
(-6045 6160);
DISPLAY 0.489362 (-6045 6160);
FORCEPROP 1 LAST WATTAGE 1/16W
J 0
(-6000 6250);
DISPLAY 0.489362 (-6000 6250);
PAINT SKYBLUE (-6000 6250);
FORCEPROP 1 LAST MATERIAL CHIP
J 0
(-6000 6200);
DISPLAY 0.489362 (-6000 6200);
PAINT SKYBLUE (-6000 6200);
FORCEPROP 1 LAST VALUE 1K
J 0
(-6000 6350);
DISPLAY 0.489362 (-6000 6350);
PAINT SKYBLUE (-6000 6350);
FORCEPROP 1 LAST PACK_TYPE 0402LF
J 0
(-6000 6150);
DISPLAY 0.489362 (-6000 6150);
PAINT SKYBLUE (-6000 6150);
FORCEPROP 1 LAST TOLERANCE 1%
J 0
(-6000 6300);
DISPLAY 0.489362 (-6000 6300);
PAINT SKYBLUE (-6000 6300);
FORCEPROP 2 LAST CDS_LIB pure_quanta
J 0
(-6050 6250);
DISPLAY INVISIBLE (-6050 6250);
FORCEPROP 1 LAST PATH I146
J 0
(-6000 6425);
DISPLAY 0.978723 (-6000 6425);
PAINT WHITE (-6000 6425);
DISPLAY INVISIBLE (-6000 6425);
FORCEPROP 1 LAST PART_NUMBER CS21002FB06
J 0
(-6000 6100);
DISPLAY 0.489362 (-6000 6100);
PAINT SKYBLUE (-6000 6100);
DISPLAY INVISIBLE (-6000 6100);
FORCEADD Q_RES..1
(-6300 5650);
FORCEPROP 1 LAST LOCATION R477
J 0
(-6525 5650);
DISPLAY 0.489362 (-6525 5650);
PAINT SKYBLUE (-6525 5650);
FORCEPROP 2 LAST $SEC 1
J 0
(-6350 5850);
DISPLAY 0.680851 (-6350 5850);
PAINT MONO (-6350 5850);
DISPLAY INVISIBLE (-6350 5850);
FORCEPROP 2 LAST CDS_SEC 1
J 0
(-6350 5850);
DISPLAY 1.021277 (-6350 5850);
DISPLAY INVISIBLE (-6350 5850);
FORCEPROP 1 LASTPIN (-6400 5650) $PN 1
J 0
(-6388 5662);
DISPLAY 0.489362 (-6388 5662);
PAINT MONO (-6388 5662);
FORCEPROP 1 LASTPIN (-6200 5650) $PN 2
J 0
(-6238 5662);
DISPLAY 0.489362 (-6238 5662);
PAINT MONO (-6238 5662);
FORCEPROP 1 LAST VALUE 33
J 2
(-6125 5650);
DISPLAY 0.489362 (-6125 5650);
PAINT SKYBLUE (-6125 5650);
FORCEPROP 2 LAST CDS_LIB pure_quanta
J 0
(-6300 5650);
DISPLAY INVISIBLE (-6300 5650);
FORCEPROP 1 LAST WATTAGE 1/16W
J 2
(-6325 5500);
DISPLAY 0.978723 (-6325 5500);
PAINT SKYBLUE (-6325 5500);
DISPLAY INVISIBLE (-6325 5500);
FORCEPROP 1 LAST MATERIAL CHIP
J 0
(-6350 5600);
DISPLAY 0.489362 (-6350 5600);
PAINT SKYBLUE (-6350 5600);
DISPLAY INVISIBLE (-6350 5600);
FORCEPROP 1 LAST TOLERANCE 5%
J 0
(-6300 5550);
DISPLAY 0.978723 (-6300 5550);
PAINT SKYBLUE (-6300 5550);
DISPLAY INVISIBLE (-6300 5550);
FORCEPROP 1 LAST PACK_TYPE 0402LF
J 0
(-6225 5600);
DISPLAY 0.489362 (-6225 5600);
PAINT SKYBLUE (-6225 5600);
DISPLAY INVISIBLE (-6225 5600);
FORCEPROP 1 LAST PATH I147
J 0
(-6350 5800);
DISPLAY 0.978723 (-6350 5800);
PAINT WHITE (-6350 5800);
DISPLAY INVISIBLE (-6350 5800);
FORCEPROP 1 LAST PART_NUMBER CS03302JB10
J 0
(-6350 5750);
DISPLAY 0.978723 (-6350 5750);
PAINT SKYBLUE (-6350 5750);
DISPLAY INVISIBLE (-6350 5750);
FORCEADD Q_RES..1
(-6300 5700);
FORCEPROP 1 LAST LOCATION R476
J 0
(-6525 5700);
DISPLAY 0.489362 (-6525 5700);
PAINT SKYBLUE (-6525 5700);
FORCEPROP 2 LAST $SEC 1
J 0
(-6350 5900);
DISPLAY 0.680851 (-6350 5900);
PAINT MONO (-6350 5900);
DISPLAY INVISIBLE (-6350 5900);
FORCEPROP 2 LAST CDS_SEC 1
J 0
(-6350 5900);
DISPLAY 1.021277 (-6350 5900);
DISPLAY INVISIBLE (-6350 5900);
FORCEPROP 1 LASTPIN (-6400 5700) $PN 1
J 0
(-6388 5712);
DISPLAY 0.489362 (-6388 5712);
PAINT MONO (-6388 5712);
FORCEPROP 1 LASTPIN (-6200 5700) $PN 2
J 0
(-6238 5712);
DISPLAY 0.489362 (-6238 5712);
PAINT MONO (-6238 5712);
FORCEPROP 1 LAST VALUE 33
J 2
(-6125 5700);
DISPLAY 0.489362 (-6125 5700);
PAINT SKYBLUE (-6125 5700);
FORCEPROP 2 LAST CDS_LIB pure_quanta
J 0
(-6300 5700);
DISPLAY INVISIBLE (-6300 5700);
FORCEPROP 1 LAST WATTAGE 1/16W
J 2
(-6325 5550);
DISPLAY 0.978723 (-6325 5550);
PAINT SKYBLUE (-6325 5550);
DISPLAY INVISIBLE (-6325 5550);
FORCEPROP 1 LAST MATERIAL CHIP
J 0
(-6350 5650);
DISPLAY 0.489362 (-6350 5650);
PAINT SKYBLUE (-6350 5650);
DISPLAY INVISIBLE (-6350 5650);
FORCEPROP 1 LAST TOLERANCE 5%
J 0
(-6300 5600);
DISPLAY 0.978723 (-6300 5600);
PAINT SKYBLUE (-6300 5600);
DISPLAY INVISIBLE (-6300 5600);
FORCEPROP 1 LAST PACK_TYPE 0402LF
J 0
(-6225 5650);
DISPLAY 0.489362 (-6225 5650);
PAINT SKYBLUE (-6225 5650);
DISPLAY INVISIBLE (-6225 5650);
FORCEPROP 1 LAST PATH I148
J 0
(-6350 5850);
DISPLAY 0.978723 (-6350 5850);
PAINT WHITE (-6350 5850);
DISPLAY INVISIBLE (-6350 5850);
FORCEPROP 1 LAST PART_NUMBER CS03302JB10
J 0
(-6350 5800);
DISPLAY 0.978723 (-6350 5800);
PAINT SKYBLUE (-6350 5800);
DISPLAY INVISIBLE (-6350 5800);
FORCEADD Q_RES..1
(-6300 5750);
FORCEPROP 1 LAST LOCATION R1620
J 0
(-6525 5750);
DISPLAY 0.489362 (-6525 5750);
PAINT SKYBLUE (-6525 5750);
FORCEPROP 2 LAST $SEC 1
J 0
(-6350 5950);
DISPLAY 0.680851 (-6350 5950);
PAINT MONO (-6350 5950);
DISPLAY INVISIBLE (-6350 5950);
FORCEPROP 2 LAST CDS_SEC 1
J 0
(-6350 5950);
DISPLAY 1.021277 (-6350 5950);
DISPLAY INVISIBLE (-6350 5950);
FORCEPROP 1 LASTPIN (-6400 5750) $PN 1
J 0
(-6388 5762);
DISPLAY 0.489362 (-6388 5762);
FORCEPROP 1 LASTPIN (-6200 5750) $PN 2
J 0
(-6238 5762);
DISPLAY 0.489362 (-6238 5762);
FORCEPROP 1 LAST VALUE 33
J 2
(-6125 5750);
DISPLAY 0.489362 (-6125 5750);
PAINT SKYBLUE (-6125 5750);
FORCEPROP 2 LAST CDS_LIB pure_quanta
J 0
(-6300 5750);
DISPLAY INVISIBLE (-6300 5750);
FORCEPROP 1 LAST WATTAGE 1/16W
J 2
(-6325 5600);
DISPLAY 0.978723 (-6325 5600);
PAINT SKYBLUE (-6325 5600);
DISPLAY INVISIBLE (-6325 5600);
FORCEPROP 1 LAST MATERIAL CHIP
J 0
(-6350 5700);
DISPLAY 0.489362 (-6350 5700);
PAINT SKYBLUE (-6350 5700);
DISPLAY INVISIBLE (-6350 5700);
FORCEPROP 1 LAST TOLERANCE 5%
J 0
(-6300 5650);
DISPLAY 0.978723 (-6300 5650);
PAINT SKYBLUE (-6300 5650);
DISPLAY INVISIBLE (-6300 5650);
FORCEPROP 1 LAST PACK_TYPE 0402LF
J 0
(-6225 5700);
DISPLAY 0.489362 (-6225 5700);
PAINT SKYBLUE (-6225 5700);
DISPLAY INVISIBLE (-6225 5700);
FORCEPROP 1 LAST PATH I149
J 0
(-6350 5900);
DISPLAY 0.978723 (-6350 5900);
PAINT WHITE (-6350 5900);
DISPLAY INVISIBLE (-6350 5900);
FORCEPROP 1 LAST PART_NUMBER CS03302JB10
J 0
(-6350 5850);
DISPLAY 0.978723 (-6350 5850);
PAINT SKYBLUE (-6350 5850);
DISPLAY INVISIBLE (-6350 5850);
FORCEADD Q_RES..1
(-6300 5600);
FORCEPROP 1 LAST LOCATION R478
J 0
(-6525 5600);
DISPLAY 0.489362 (-6525 5600);
PAINT SKYBLUE (-6525 5600);
FORCEPROP 2 LAST $SEC 1
J 0
(-6350 5800);
DISPLAY 0.680851 (-6350 5800);
PAINT MONO (-6350 5800);
DISPLAY INVISIBLE (-6350 5800);
FORCEPROP 2 LAST CDS_SEC 1
J 0
(-6350 5800);
DISPLAY 1.021277 (-6350 5800);
DISPLAY INVISIBLE (-6350 5800);
FORCEPROP 1 LASTPIN (-6400 5600) $PN 1
J 0
(-6388 5612);
DISPLAY 0.489362 (-6388 5612);
PAINT MONO (-6388 5612);
FORCEPROP 1 LASTPIN (-6200 5600) $PN 2
J 0
(-6238 5612);
DISPLAY 0.489362 (-6238 5612);
PAINT MONO (-6238 5612);
FORCEPROP 1 LAST VALUE 33
J 2
(-6125 5600);
DISPLAY 0.489362 (-6125 5600);
PAINT SKYBLUE (-6125 5600);
FORCEPROP 2 LAST CDS_LIB pure_quanta
J 0
(-6300 5600);
DISPLAY INVISIBLE (-6300 5600);
FORCEPROP 1 LAST WATTAGE 1/16W
J 2
(-6325 5450);
DISPLAY 0.978723 (-6325 5450);
PAINT SKYBLUE (-6325 5450);
DISPLAY INVISIBLE (-6325 5450);
FORCEPROP 1 LAST MATERIAL CHIP
J 0
(-6350 5550);
DISPLAY 0.489362 (-6350 5550);
PAINT SKYBLUE (-6350 5550);
DISPLAY INVISIBLE (-6350 5550);
FORCEPROP 1 LAST TOLERANCE 5%
J 0
(-6300 5500);
DISPLAY 0.978723 (-6300 5500);
PAINT SKYBLUE (-6300 5500);
DISPLAY INVISIBLE (-6300 5500);
FORCEPROP 1 LAST PACK_TYPE 0402LF
J 0
(-6225 5550);
DISPLAY 0.489362 (-6225 5550);
PAINT SKYBLUE (-6225 5550);
DISPLAY INVISIBLE (-6225 5550);
FORCEPROP 1 LAST PATH I150
J 0
(-6350 5750);
DISPLAY 0.978723 (-6350 5750);
PAINT WHITE (-6350 5750);
DISPLAY INVISIBLE (-6350 5750);
FORCEPROP 1 LAST PART_NUMBER CS03302JB10
J 0
(-6350 5700);
DISPLAY 0.978723 (-6350 5700);
PAINT SKYBLUE (-6350 5700);
DISPLAY INVISIBLE (-6350 5700);
FORCEADD GND..1
(-7000 5150);
FORCEPROP 3 LASTPIN (-7000 5200) SIG_NAME GND\g
J 0
(-6990 5210);
DISPLAY 0.659574 (-6990 5210);
PAINT MONO (-6990 5210);
DISPLAY INVISIBLE (-6990 5210);
FORCEPROP 2 LAST CDS_LIB pure_quanta_power
J 0
(-7000 5150);
DISPLAY INVISIBLE (-7000 5150);
FORCEPROP 1 LAST SIZE 1B
J 0
(-6925 5100);
DISPLAY 0.872340 (-6925 5100);
PAINT GREEN (-6925 5100);
DISPLAY INVISIBLE (-6925 5100);
FORCEPROP 1 LAST HDL_POWER GND
J 0
(-7000 5300);
DISPLAY 0.872340 (-7000 5300);
PAINT GREEN (-7000 5300);
DISPLAY INVISIBLE (-7000 5300);
FORCEPROP 1 LAST PATH I151
J 0
(-6925 5150);
DISPLAY 0.872340 (-6925 5150);
PAINT AQUA (-6925 5150);
DISPLAY INVISIBLE (-6925 5150);
FORCEADD Q_CAP..1
(-7000 5375);
FORCEPROP 1 LAST LOCATION C85
J 0
(-6950 5475);
DISPLAY 0.489362 (-6950 5475);
PAINT SKYBLUE (-6950 5475);
FORCEPROP 0 LAST $SEC 1
J 0
(-6950 5500);
DISPLAY 0.680851 (-6950 5500);
PAINT MONO (-6950 5500);
DISPLAY INVISIBLE (-6950 5500);
FORCEPROP 0 LAST CDS_SEC 1
J 0
(-6950 5500);
DISPLAY 0.680851 (-6950 5500);
DISPLAY INVISIBLE (-6950 5500);
FORCEPROP 1 LASTPIN (-7000 5475) $PN 1
J 0
(-6990 5455);
DISPLAY 0.489362 (-6990 5455);
PAINT MONO (-6990 5455);
FORCEPROP 1 LASTPIN (-7000 5275) $PN 2
J 0
(-6990 5255);
DISPLAY 0.489362 (-6990 5255);
PAINT MONO (-6990 5255);
FORCEPROP 1 LAST PACK_TYPE C0402
J 0
(-6950 5225);
DISPLAY 0.489362 (-6950 5225);
PAINT SKYBLUE (-6950 5225);
FORCEPROP 1 LAST VOLTAGE 50V
J 0
(-6950 5375);
DISPLAY 0.489362 (-6950 5375);
PAINT SKYBLUE (-6950 5375);
FORCEPROP 1 LAST VALUE 0.001UF
J 0
(-6950 5425);
DISPLAY 0.489362 (-6950 5425);
PAINT SKYBLUE (-6950 5425);
FORCEPROP 1 LAST TOLERANCE 10%
J 0
(-6950 5325);
DISPLAY 0.489362 (-6950 5325);
PAINT SKYBLUE (-6950 5325);
FORCEPROP 1 LAST MATERIAL X7R
J 0
(-6950 5275);
DISPLAY 0.489362 (-6950 5275);
PAINT SKYBLUE (-6950 5275);
FORCEPROP 2 LAST CDS_LIB pure_quanta
J 0
(-7000 5375);
DISPLAY INVISIBLE (-7000 5375);
FORCEPROP 1 LAST PATH I152
J 0
(-6950 5525);
DISPLAY 0.978723 (-6950 5525);
PAINT WHITE (-6950 5525);
DISPLAY INVISIBLE (-6950 5525);
FORCEPROP 1 LAST PART_NUMBER CH30106KB19
J 0
(-6950 5275);
DISPLAY 0.808511 (-6950 5275);
PAINT SKYBLUE (-6950 5275);
DISPLAY INVISIBLE (-6950 5275);
FORCEADD OFFPAGE..6
(-7125 5700);
FORCEPROP 2 LAST $XR1 82 
J 0
(-7494 5700);
DISPLAY 0.638298 (-7494 5700);
PAINT MONO (-7494 5700);
FORCEPROP 2 LAST $XR0 27 
J 0
(-7404 5700);
DISPLAY 0.638298 (-7404 5700);
PAINT MONO (-7404 5700);
FORCEPROP 2 LAST CDS_LIB standard
J 0
(-7125 5700);
DISPLAY INVISIBLE (-7125 5700);
FORCEPROP 1 LAST OFFPAGE TRUE
J 0
(-6800 5575);
DISPLAY 0.872340 (-6800 5575);
PAINT GREEN (-6800 5575);
DISPLAY INVISIBLE (-6800 5575);
FORCEPROP 1 LAST COMMENT_BODY TRUE
J 0
(-7025 5625);
DISPLAY 0.872340 (-7025 5625);
PAINT GREEN (-7025 5625);
DISPLAY INVISIBLE (-7025 5625);
FORCEPROP 2 LAST PATH I153
J 0
(-7350 5750);
DISPLAY 0.680851 (-7350 5750);
DISPLAY INVISIBLE (-7350 5750);
FORCEADD OFFPAGE..5
(-7150 5750);
FORCEPROP 2 LAST $XR0 172 
J 0
(-7405 5750);
DISPLAY 0.638298 (-7405 5750);
PAINT MONO (-7405 5750);
FORCEPROP 2 LAST CDS_LIB standard
J 0
(-7150 5750);
DISPLAY INVISIBLE (-7150 5750);
FORCEPROP 1 LAST OFFPAGE TRUE
J 0
(-6825 5625);
DISPLAY 0.872340 (-6825 5625);
PAINT GREEN (-6825 5625);
DISPLAY INVISIBLE (-6825 5625);
FORCEPROP 1 LAST COMMENT_BODY TRUE
J 0
(-7050 5675);
DISPLAY 0.872340 (-7050 5675);
PAINT GREEN (-7050 5675);
DISPLAY INVISIBLE (-7050 5675);
FORCEPROP 2 LAST PATH I154
J 0
(-7400 5800);
DISPLAY 0.680851 (-7400 5800);
DISPLAY INVISIBLE (-7400 5800);
FORCEADD OFFPAGE..6
(-7125 5650);
FORCEPROP 2 LAST $XR1 82 
J 0
(-7494 5650);
DISPLAY 0.638298 (-7494 5650);
PAINT MONO (-7494 5650);
FORCEPROP 2 LAST $XR0 27 
J 0
(-7404 5650);
DISPLAY 0.638298 (-7404 5650);
PAINT MONO (-7404 5650);
FORCEPROP 2 LAST CDS_LIB standard
J 0
(-7125 5650);
DISPLAY INVISIBLE (-7125 5650);
FORCEPROP 1 LAST OFFPAGE TRUE
J 0
(-6800 5525);
DISPLAY 0.872340 (-6800 5525);
PAINT GREEN (-6800 5525);
DISPLAY INVISIBLE (-6800 5525);
FORCEPROP 1 LAST COMMENT_BODY TRUE
J 0
(-7025 5575);
DISPLAY 0.872340 (-7025 5575);
PAINT GREEN (-7025 5575);
DISPLAY INVISIBLE (-7025 5575);
FORCEPROP 2 LAST PATH I155
J 0
(-7350 5700);
DISPLAY 0.680851 (-7350 5700);
DISPLAY INVISIBLE (-7350 5700);
FORCEADD OFFPAGE..6
(-7125 5600);
FORCEPROP 2 LAST $XR1 82 
J 0
(-7494 5600);
DISPLAY 0.638298 (-7494 5600);
PAINT MONO (-7494 5600);
FORCEPROP 2 LAST $XR0 27 
J 0
(-7404 5600);
DISPLAY 0.638298 (-7404 5600);
PAINT MONO (-7404 5600);
FORCEPROP 2 LAST CDS_LIB standard
J 0
(-7125 5600);
DISPLAY INVISIBLE (-7125 5600);
FORCEPROP 1 LAST OFFPAGE TRUE
J 0
(-6800 5475);
DISPLAY 0.872340 (-6800 5475);
PAINT GREEN (-6800 5475);
DISPLAY INVISIBLE (-6800 5475);
FORCEPROP 1 LAST COMMENT_BODY TRUE
J 0
(-7025 5525);
DISPLAY 0.872340 (-7025 5525);
PAINT GREEN (-7025 5525);
DISPLAY INVISIBLE (-7025 5525);
FORCEPROP 2 LAST PATH I156
J 0
(-7350 5650);
DISPLAY 0.680851 (-7350 5650);
DISPLAY INVISIBLE (-7350 5650);
FORCEADD Q_RES..1
(-6300 5900);
FORCEPROP 1 LAST LOCATION R1528
J 0
(-6525 5900);
DISPLAY 0.489362 (-6525 5900);
PAINT SKYBLUE (-6525 5900);
FORCEPROP 0 LAST $SEC 1
J 0
(-6125 5925);
DISPLAY 0.680851 (-6125 5925);
PAINT MONO (-6125 5925);
DISPLAY INVISIBLE (-6125 5925);
FORCEPROP 0 LAST CDS_SEC 1
J 0
(-6125 5925);
DISPLAY 0.680851 (-6125 5925);
DISPLAY INVISIBLE (-6125 5925);
FORCEPROP 1 LASTPIN (-6400 5900) $PN 1
J 0
(-6388 5912);
DISPLAY 0.489362 (-6388 5912);
PAINT MONO (-6388 5912);
FORCEPROP 1 LASTPIN (-6200 5900) $PN 2
J 0
(-6238 5912);
DISPLAY 0.489362 (-6238 5912);
PAINT MONO (-6238 5912);
FORCEPROP 1 LAST VALUE 33
J 2
(-6125 5900);
DISPLAY 0.489362 (-6125 5900);
PAINT SKYBLUE (-6125 5900);
FORCEPROP 2 LAST CDS_LIB pure_quanta
J 0
(-6300 5900);
DISPLAY INVISIBLE (-6300 5900);
FORCEPROP 1 LAST WATTAGE 1/16W
J 2
(-6325 5750);
DISPLAY 0.978723 (-6325 5750);
PAINT SKYBLUE (-6325 5750);
DISPLAY INVISIBLE (-6325 5750);
FORCEPROP 1 LAST MATERIAL CHIP
J 0
(-6350 5850);
DISPLAY 0.489362 (-6350 5850);
PAINT SKYBLUE (-6350 5850);
DISPLAY INVISIBLE (-6350 5850);
FORCEPROP 1 LAST TOLERANCE 5%
J 0
(-6300 5800);
DISPLAY 0.978723 (-6300 5800);
PAINT SKYBLUE (-6300 5800);
DISPLAY INVISIBLE (-6300 5800);
FORCEPROP 1 LAST PACK_TYPE 0402LF
J 0
(-6225 5850);
DISPLAY 0.489362 (-6225 5850);
PAINT SKYBLUE (-6225 5850);
DISPLAY INVISIBLE (-6225 5850);
FORCEPROP 1 LAST PATH I157
J 0
(-6350 6050);
DISPLAY 0.978723 (-6350 6050);
PAINT WHITE (-6350 6050);
DISPLAY INVISIBLE (-6350 6050);
FORCEPROP 1 LAST PART_NUMBER CS03302JB10
J 0
(-6350 6000);
DISPLAY 0.978723 (-6350 6000);
PAINT SKYBLUE (-6350 6000);
DISPLAY INVISIBLE (-6350 6000);
FORCEADD OFFPAGE..5
(-7150 5900);
FORCEPROP 2 LAST $XR1 81 
J 0
(-7494 5900);
DISPLAY 0.638298 (-7494 5900);
PAINT MONO (-7494 5900);
FORCEPROP 2 LAST $XR0 83 
J 0
(-7404 5900);
DISPLAY 0.638298 (-7404 5900);
PAINT MONO (-7404 5900);
FORCEPROP 2 LAST CDS_LIB standard
J 0
(-7150 5900);
DISPLAY INVISIBLE (-7150 5900);
FORCEPROP 1 LAST OFFPAGE TRUE
J 0
(-6825 5775);
DISPLAY 0.872340 (-6825 5775);
PAINT GREEN (-6825 5775);
DISPLAY INVISIBLE (-6825 5775);
FORCEPROP 1 LAST COMMENT_BODY TRUE
J 0
(-7050 5825);
DISPLAY 0.872340 (-7050 5825);
PAINT GREEN (-7050 5825);
DISPLAY INVISIBLE (-7050 5825);
FORCEPROP 2 LAST PATH I158
J 0
(-7100 5975);
DISPLAY 0.680851 (-7100 5975);
DISPLAY INVISIBLE (-7100 5975);
FORCEADD Q_RES..1
(-8400 3975);
FORCEPROP 1 LAST LOCATION R6108
J 0
(-8450 4025);
DISPLAY 0.489362 (-8450 4025);
PAINT SKYBLUE (-8450 4025);
FORCEPROP 0 LAST $SEC 1
J 0
(-8450 4075);
PAINT MONO (-8450 4075);
DISPLAY INVISIBLE (-8450 4075);
FORCEPROP 0 LAST CDS_SEC 1
J 0
(-8450 4075);
PAINT MONO (-8450 4075);
DISPLAY INVISIBLE (-8450 4075);
FORCEPROP 1 LASTPIN (-8500 3975) $PN 1
J 0
(-8488 3987);
DISPLAY 0.489362 (-8488 3987);
PAINT GREEN (-8488 3987);
FORCEPROP 1 LASTPIN (-8300 3975) $PN 2
J 0
(-8338 3987);
DISPLAY 0.489362 (-8338 3987);
PAINT GREEN (-8338 3987);
FORCEPROP 1 LAST VALUE 0
J 2
(-8250 3975);
DISPLAY 0.489362 (-8250 3975);
PAINT SKYBLUE (-8250 3975);
FORCEPROP 1 LAST MATERIAL CHIP
J 0
(-8325 3950);
DISPLAY 0.489362 (-8325 3950);
PAINT SKYBLUE (-8325 3950);
FORCEPROP 2 LAST CDS_LIB pure_quanta
J 0
(-8400 3975);
PAINT MONO (-8400 3975);
DISPLAY INVISIBLE (-8400 3975);
FORCEPROP 1 LAST PACK_TYPE 0402LF
J 0
(-8150 3825);
DISPLAY 0.978723 (-8150 3825);
PAINT SKYBLUE (-8150 3825);
DISPLAY INVISIBLE (-8150 3825);
FORCEPROP 1 LAST TOLERANCE 5%
J 0
(-8400 3875);
DISPLAY 0.978723 (-8400 3875);
PAINT SKYBLUE (-8400 3875);
DISPLAY INVISIBLE (-8400 3875);
FORCEPROP 1 LAST WATTAGE 1/16W
J 2
(-8425 3825);
DISPLAY 0.978723 (-8425 3825);
PAINT SKYBLUE (-8425 3825);
DISPLAY INVISIBLE (-8425 3825);
FORCEPROP 1 LAST PATH I159
J 0
(-8450 4125);
DISPLAY 0.978723 (-8450 4125);
PAINT WHITE (-8450 4125);
DISPLAY INVISIBLE (-8450 4125);
FORCEPROP 1 LAST PART_NUMBER CS00002JB13
J 0
(-8450 4075);
DISPLAY 0.978723 (-8450 4075);
PAINT SKYBLUE (-8450 4075);
DISPLAY INVISIBLE (-8450 4075);
FORCEADD Q_RES..1
(-5675 3925);
FORCEPROP 1 LAST LOCATION R6111
J 0
(-5900 3925);
DISPLAY 0.489362 (-5900 3925);
PAINT SKYBLUE (-5900 3925);
FORCEPROP 0 LAST $SEC 1
J 0
(-5525 3975);
PAINT MONO (-5525 3975);
DISPLAY INVISIBLE (-5525 3975);
FORCEPROP 0 LAST CDS_SEC 1
J 0
(-5525 3975);
PAINT MONO (-5525 3975);
DISPLAY INVISIBLE (-5525 3975);
FORCEPROP 1 LASTPIN (-5775 3925) $PN 1
J 0
(-5763 3937);
DISPLAY 0.489362 (-5763 3937);
PAINT GREEN (-5763 3937);
FORCEPROP 1 LASTPIN (-5575 3925) $PN 2
J 0
(-5613 3937);
DISPLAY 0.489362 (-5613 3937);
PAINT GREEN (-5613 3937);
FORCEPROP 1 LAST VALUE 0
J 2
(-5525 3925);
DISPLAY 0.489362 (-5525 3925);
PAINT SKYBLUE (-5525 3925);
FORCEPROP 1 LAST PACK_TYPE 0402LF
J 0
(-5425 3775);
DISPLAY 0.978723 (-5425 3775);
PAINT SKYBLUE (-5425 3775);
DISPLAY INVISIBLE (-5425 3775);
FORCEPROP 1 LAST TOLERANCE 5%
J 0
(-5675 3825);
DISPLAY 0.978723 (-5675 3825);
PAINT SKYBLUE (-5675 3825);
DISPLAY INVISIBLE (-5675 3825);
FORCEPROP 1 LAST MATERIAL CHIP
J 0
(-5450 3925);
DISPLAY 0.617021 (-5450 3925);
PAINT SKYBLUE (-5450 3925);
DISPLAY INVISIBLE (-5450 3925);
FORCEPROP 1 LAST WATTAGE 1/16W
J 2
(-5700 3775);
DISPLAY 0.978723 (-5700 3775);
PAINT SKYBLUE (-5700 3775);
DISPLAY INVISIBLE (-5700 3775);
FORCEPROP 2 LAST CDS_LIB pure_quanta
J 0
(-5675 3925);
PAINT MONO (-5675 3925);
DISPLAY INVISIBLE (-5675 3925);
FORCEPROP 1 LAST PATH I160
J 0
(-5725 4075);
DISPLAY 0.978723 (-5725 4075);
PAINT WHITE (-5725 4075);
DISPLAY INVISIBLE (-5725 4075);
FORCEPROP 1 LAST PART_NUMBER CS00002JB13
J 0
(-5725 4025);
DISPLAY 0.978723 (-5725 4025);
PAINT SKYBLUE (-5725 4025);
DISPLAY INVISIBLE (-5725 4025);
FORCEADD Q_CAP..1
(-5125 4425);
FORCEPROP 1 LAST LOCATION C86
J 0
(-5050 4525);
DISPLAY 0.489362 (-5050 4525);
PAINT SKYBLUE (-5050 4525);
FORCEPROP 0 LAST $SEC 1
J 0
(-5050 4575);
PAINT MONO (-5050 4575);
DISPLAY INVISIBLE (-5050 4575);
FORCEPROP 0 LAST CDS_SEC 1
J 0
(-5050 4575);
PAINT MONO (-5050 4575);
DISPLAY INVISIBLE (-5050 4575);
FORCEPROP 1 LASTPIN (-5125 4525) $PN 1
J 0
(-5115 4505);
DISPLAY 0.489362 (-5115 4505);
PAINT GREEN (-5115 4505);
FORCEPROP 1 LASTPIN (-5125 4325) $PN 2
J 0
(-5115 4305);
DISPLAY 0.489362 (-5115 4305);
PAINT GREEN (-5115 4305);
FORCEPROP 1 LAST PACK_TYPE C0402
J 0
(-5050 4275);
DISPLAY 0.489362 (-5050 4275);
PAINT SKYBLUE (-5050 4275);
FORCEPROP 1 LAST MATERIAL EMPTY
J 0
(-5050 4325);
DISPLAY 0.489362 (-5050 4325);
PAINT RED (-5050 4325);
FORCEPROP 1 LAST TOLERANCE 10%
J 0
(-5050 4375);
DISPLAY 0.489362 (-5050 4375);
PAINT SKYBLUE (-5050 4375);
FORCEPROP 1 LAST VOLTAGE 50V
J 0
(-5050 4425);
DISPLAY 0.489362 (-5050 4425);
PAINT SKYBLUE (-5050 4425);
FORCEPROP 1 LAST VALUE 0.01UF
J 0
(-5050 4475);
DISPLAY 0.489362 (-5050 4475);
PAINT SKYBLUE (-5050 4475);
FORCEPROP 2 LAST CDS_LIB pure_quanta
J 0
(-5125 4425);
PAINT MONO (-5125 4425);
DISPLAY INVISIBLE (-5125 4425);
FORCEPROP 1 LAST PATH I161
J 0
(-5075 4575);
DISPLAY 0.978723 (-5075 4575);
PAINT WHITE (-5075 4575);
DISPLAY INVISIBLE (-5075 4575);
FORCEPROP 1 LAST PART_NUMBER CH31006KB18
R 1
J 0
(-5175 4175);
DISPLAY 0.617021 (-5175 4175);
PAINT SKYBLUE (-5175 4175);
DISPLAY INVISIBLE (-5175 4175);
FORCEADD GND..1
(-5125 4200);
FORCEPROP 3 LASTPIN (-5125 4250) SIG_NAME GND\g
J 0
(-5115 4260);
DISPLAY 0.659574 (-5115 4260);
PAINT MONO (-5115 4260);
DISPLAY INVISIBLE (-5115 4260);
FORCEPROP 1 LAST SIZE 1B
J 0
(-5050 4150);
DISPLAY 0.872340 (-5050 4150);
PAINT GREEN (-5050 4150);
DISPLAY INVISIBLE (-5050 4150);
FORCEPROP 2 LAST CDS_LIB pure_quanta_power
J 0
(-5125 4200);
DISPLAY INVISIBLE (-5125 4200);
FORCEPROP 1 LAST HDL_POWER GND
J 0
(-5125 4350);
DISPLAY 0.872340 (-5125 4350);
PAINT GREEN (-5125 4350);
DISPLAY INVISIBLE (-5125 4350);
FORCEPROP 1 LAST PATH I162
J 0
(-5050 4200);
DISPLAY 0.872340 (-5050 4200);
PAINT AQUA (-5050 4200);
DISPLAY INVISIBLE (-5050 4200);
FORCEADD Q_CAP..1
R 2
(-8075 3150);
FORCEPROP 1 LAST LOCATION C8006
J 2
(-8125 3250);
DISPLAY 0.638298 (-8125 3250);
FORCEPROP 0 LAST $SEC 1
J 0
(-8125 3300);
DISPLAY 0.680851 (-8125 3300);
PAINT MONO (-8125 3300);
DISPLAY INVISIBLE (-8125 3300);
FORCEPROP 0 LAST CDS_SEC 1
J 0
(-8125 3300);
DISPLAY 0.680851 (-8125 3300);
DISPLAY INVISIBLE (-8125 3300);
FORCEPROP 1 LASTPIN (-8075 3250) $PN 1
J 2
(-8085 3230);
DISPLAY 0.787234 (-8085 3230);
PAINT MONO (-8085 3230);
FORCEPROP 1 LASTPIN (-8075 3050) $PN 2
J 2
(-8085 3030);
DISPLAY 0.787234 (-8085 3030);
PAINT MONO (-8085 3030);
FORCEPROP 1 LAST VALUE 0.1UF
J 2
(-8125 3200);
DISPLAY 0.638298 (-8125 3200);
FORCEPROP 1 LAST PACK_TYPE 0402
J 2
(-8125 3000);
DISPLAY 0.638298 (-8125 3000);
FORCEPROP 1 LAST TOLERANCE 10%
J 2
(-8125 3100);
DISPLAY 0.638298 (-8125 3100);
FORCEPROP 1 LAST MATERIAL X7R
J 2
(-8125 3050);
DISPLAY 0.638298 (-8125 3050);
FORCEPROP 1 LAST VOLTAGE 25V
J 2
(-8125 3150);
DISPLAY 0.638298 (-8125 3150);
FORCEPROP 2 LAST CDS_LIB pure_quanta
J 2
(-8075 3150);
DISPLAY INVISIBLE (-8075 3150);
FORCEPROP 1 LAST PATH I163
J 2
(-8125 3300);
DISPLAY 0.978723 (-8125 3300);
PAINT WHITE (-8125 3300);
DISPLAY INVISIBLE (-8125 3300);
FORCEPROP 1 LAST PART_NUMBER CH4104K1B00
J 2
(-8125 3000);
DISPLAY 0.978723 (-8125 3000);
DISPLAY INVISIBLE (-8125 3000);
FORCEADD GND..1
(-8075 2925);
FORCEPROP 3 LASTPIN (-8075 2975) SIG_NAME GND\g
J 0
(-8065 2985);
DISPLAY 0.659574 (-8065 2985);
PAINT MONO (-8065 2985);
DISPLAY INVISIBLE (-8065 2985);
FORCEPROP 1 LAST SIZE 1B
J 0
(-8000 2875);
DISPLAY 0.872340 (-8000 2875);
PAINT GREEN (-8000 2875);
DISPLAY INVISIBLE (-8000 2875);
FORCEPROP 2 LAST CDS_LIB pure_quanta_power
J 0
(-8075 2925);
DISPLAY INVISIBLE (-8075 2925);
FORCEPROP 1 LAST HDL_POWER GND
J 0
(-8075 3075);
DISPLAY 0.872340 (-8075 3075);
PAINT GREEN (-8075 3075);
DISPLAY INVISIBLE (-8075 3075);
FORCEPROP 1 LAST PATH I164
J 0
(-8000 2925);
DISPLAY 0.872340 (-8000 2925);
PAINT AQUA (-8000 2925);
DISPLAY INVISIBLE (-8000 2925);
FORCEADD UNIVERSAL_POWER..1
(-3750 4825);
FORCEPROP 3 LASTPIN (-3750 4775) SIG_NAME PVDD18_S5_P0\g
J 0
(-3740 4785);
DISPLAY 0.659574 (-3740 4785);
PAINT MONO (-3740 4785);
DISPLAY INVISIBLE (-3740 4785);
FORCEPROP 1 LAST HDL_POWER PVDD18_S5_P0
J 1
(-3750 4875);
DISPLAY 0.489362 (-3750 4875);
PAINT GREEN (-3750 4875);
FORCEPROP 2 LAST CDS_LIB pure_quanta_power
J 0
(-3750 4825);
PAINT MONO (-3750 4825);
DISPLAY INVISIBLE (-3750 4825);
FORCEPROP 1 LAST PATH I20
J 0
(-3700 4850);
DISPLAY 0.872340 (-3700 4850);
PAINT AQUA (-3700 4850);
DISPLAY INVISIBLE (-3700 4850);
FORCEADD Q_CAP..1
(-800 3775);
FORCEPROP 1 LAST LOCATION C1512
J 0
(-750 3875);
DISPLAY 0.489362 (-750 3875);
PAINT SKYBLUE (-750 3875);
FORCEPROP 0 LAST $SEC 1
J 0
(-750 3925);
PAINT MONO (-750 3925);
DISPLAY INVISIBLE (-750 3925);
FORCEPROP 0 LAST CDS_SEC 1
J 0
(-750 3925);
PAINT MONO (-750 3925);
DISPLAY INVISIBLE (-750 3925);
FORCEPROP 1 LASTPIN (-800 3875) $PN 1
J 0
(-790 3855);
DISPLAY 0.489362 (-790 3855);
PAINT GREEN (-790 3855);
FORCEPROP 1 LASTPIN (-800 3675) $PN 2
J 0
(-790 3655);
DISPLAY 0.489362 (-790 3655);
PAINT GREEN (-790 3655);
FORCEPROP 1 LAST PACK_TYPE 0402
J 0
(-750 3625);
DISPLAY 0.489362 (-750 3625);
PAINT SKYBLUE (-750 3625);
FORCEPROP 1 LAST VOLTAGE 50V
J 0
(-750 3775);
DISPLAY 0.489362 (-750 3775);
PAINT SKYBLUE (-750 3775);
FORCEPROP 1 LAST VALUE 33PF
J 0
(-750 3825);
DISPLAY 0.489362 (-750 3825);
PAINT SKYBLUE (-750 3825);
FORCEPROP 1 LAST TOLERANCE 5%
J 0
(-750 3725);
DISPLAY 0.489362 (-750 3725);
PAINT SKYBLUE (-750 3725);
FORCEPROP 1 LAST MATERIAL NPO
J 0
(-750 3475);
DISPLAY 0.489362 (-750 3475);
PAINT SKYBLUE (-750 3475);
FORCEPROP 2 LAST CDS_LIB pure_quanta
J 0
(-800 3775);
PAINT MONO (-800 3775);
DISPLAY INVISIBLE (-800 3775);
FORCEPROP 1 LAST PATH I21
J 0
(-750 3925);
DISPLAY 0.978723 (-750 3925);
PAINT WHITE (-750 3925);
DISPLAY INVISIBLE (-750 3925);
FORCEPROP 1 LAST PART_NUMBER TMP_QCH03306JB04
J 0
(-750 3675);
DISPLAY 0.489362 (-750 3675);
PAINT SKYBLUE (-750 3675);
DISPLAY INVISIBLE (-750 3675);
FORCEADD GND..1
(-800 3450);
FORCEPROP 3 LASTPIN (-800 3500) SIG_NAME GND\g
J 0
(-790 3510);
DISPLAY 0.659574 (-790 3510);
PAINT MONO (-790 3510);
DISPLAY INVISIBLE (-790 3510);
FORCEPROP 1 LAST SIZE 1B
J 0
(-725 3400);
DISPLAY 0.872340 (-725 3400);
PAINT GREEN (-725 3400);
DISPLAY INVISIBLE (-725 3400);
FORCEPROP 2 LAST CDS_LIB pure_quanta_power
J 0
(-800 3450);
DISPLAY INVISIBLE (-800 3450);
FORCEPROP 1 LAST HDL_POWER GND
J 0
(-800 3600);
DISPLAY 0.872340 (-800 3600);
PAINT GREEN (-800 3600);
DISPLAY INVISIBLE (-800 3600);
FORCEPROP 1 LAST PATH I22
J 0
(-725 3450);
DISPLAY 0.872340 (-725 3450);
PAINT AQUA (-725 3450);
DISPLAY INVISIBLE (-725 3450);
FORCEADD Q_CAP..1
(-1125 3775);
FORCEPROP 1 LAST LOCATION C1511
J 0
(-1075 3875);
DISPLAY 0.489362 (-1075 3875);
PAINT SKYBLUE (-1075 3875);
FORCEPROP 0 LAST $SEC 1
J 0
(-1075 3925);
PAINT MONO (-1075 3925);
DISPLAY INVISIBLE (-1075 3925);
FORCEPROP 0 LAST CDS_SEC 1
J 0
(-1075 3925);
PAINT MONO (-1075 3925);
DISPLAY INVISIBLE (-1075 3925);
FORCEPROP 1 LASTPIN (-1125 3875) $PN 1
J 0
(-1115 3855);
DISPLAY 0.489362 (-1115 3855);
PAINT GREEN (-1115 3855);
FORCEPROP 1 LASTPIN (-1125 3675) $PN 2
J 0
(-1115 3655);
DISPLAY 0.489362 (-1115 3655);
PAINT GREEN (-1115 3655);
FORCEPROP 1 LAST PACK_TYPE 0402
J 0
(-1075 3625);
DISPLAY 0.489362 (-1075 3625);
PAINT SKYBLUE (-1075 3625);
FORCEPROP 1 LAST VOLTAGE 50V
J 0
(-1075 3775);
DISPLAY 0.489362 (-1075 3775);
PAINT SKYBLUE (-1075 3775);
FORCEPROP 1 LAST VALUE 33PF
J 0
(-1075 3825);
DISPLAY 0.489362 (-1075 3825);
PAINT SKYBLUE (-1075 3825);
FORCEPROP 1 LAST TOLERANCE 5%
J 0
(-1075 3725);
DISPLAY 0.489362 (-1075 3725);
PAINT SKYBLUE (-1075 3725);
FORCEPROP 1 LAST MATERIAL NPO
J 0
(-1075 3475);
DISPLAY 0.489362 (-1075 3475);
PAINT SKYBLUE (-1075 3475);
FORCEPROP 2 LAST CDS_LIB pure_quanta
J 0
(-1125 3775);
PAINT MONO (-1125 3775);
DISPLAY INVISIBLE (-1125 3775);
FORCEPROP 1 LAST PATH I23
J 0
(-1075 3925);
DISPLAY 0.978723 (-1075 3925);
PAINT WHITE (-1075 3925);
DISPLAY INVISIBLE (-1075 3925);
FORCEPROP 1 LAST PART_NUMBER TMP_QCH03306JB04
J 0
(-1075 3675);
DISPLAY 0.808511 (-1075 3675);
PAINT SKYBLUE (-1075 3675);
DISPLAY INVISIBLE (-1075 3675);
FORCEADD GND..1
(-1125 3450);
FORCEPROP 3 LASTPIN (-1125 3500) SIG_NAME GND\g
J 0
(-1115 3510);
DISPLAY 0.659574 (-1115 3510);
PAINT MONO (-1115 3510);
DISPLAY INVISIBLE (-1115 3510);
FORCEPROP 1 LAST SIZE 1B
J 0
(-1050 3400);
DISPLAY 0.872340 (-1050 3400);
PAINT GREEN (-1050 3400);
DISPLAY INVISIBLE (-1050 3400);
FORCEPROP 2 LAST CDS_LIB pure_quanta_power
J 0
(-1125 3450);
DISPLAY INVISIBLE (-1125 3450);
FORCEPROP 1 LAST HDL_POWER GND
J 0
(-1125 3600);
DISPLAY 0.872340 (-1125 3600);
PAINT GREEN (-1125 3600);
DISPLAY INVISIBLE (-1125 3600);
FORCEPROP 1 LAST PATH I24
J 0
(-1050 3450);
DISPLAY 0.872340 (-1050 3450);
PAINT AQUA (-1050 3450);
DISPLAY INVISIBLE (-1050 3450);
FORCEADD Q_CAP..1
(-1500 3775);
FORCEPROP 1 LAST LOCATION C1510
J 0
(-1450 3875);
DISPLAY 0.489362 (-1450 3875);
PAINT SKYBLUE (-1450 3875);
FORCEPROP 0 LAST $SEC 1
J 0
(-1450 3925);
PAINT MONO (-1450 3925);
DISPLAY INVISIBLE (-1450 3925);
FORCEPROP 0 LAST CDS_SEC 1
J 0
(-1450 3925);
PAINT MONO (-1450 3925);
DISPLAY INVISIBLE (-1450 3925);
FORCEPROP 1 LASTPIN (-1500 3875) $PN 1
J 0
(-1490 3855);
DISPLAY 0.489362 (-1490 3855);
PAINT GREEN (-1490 3855);
FORCEPROP 1 LASTPIN (-1500 3675) $PN 2
J 0
(-1490 3655);
DISPLAY 0.489362 (-1490 3655);
PAINT GREEN (-1490 3655);
FORCEPROP 1 LAST PACK_TYPE 0402
J 0
(-1450 3625);
DISPLAY 0.489362 (-1450 3625);
PAINT SKYBLUE (-1450 3625);
FORCEPROP 1 LAST VOLTAGE 50V
J 0
(-1450 3775);
DISPLAY 0.489362 (-1450 3775);
PAINT SKYBLUE (-1450 3775);
FORCEPROP 1 LAST VALUE 33PF
J 0
(-1450 3825);
DISPLAY 0.489362 (-1450 3825);
PAINT SKYBLUE (-1450 3825);
FORCEPROP 1 LAST TOLERANCE 5%
J 0
(-1450 3725);
DISPLAY 0.489362 (-1450 3725);
PAINT SKYBLUE (-1450 3725);
FORCEPROP 1 LAST MATERIAL NPO
J 0
(-1450 3475);
DISPLAY 0.489362 (-1450 3475);
PAINT SKYBLUE (-1450 3475);
FORCEPROP 2 LAST CDS_LIB pure_quanta
J 0
(-1500 3775);
PAINT MONO (-1500 3775);
DISPLAY INVISIBLE (-1500 3775);
FORCEPROP 1 LAST PATH I25
J 0
(-1450 3925);
DISPLAY 0.978723 (-1450 3925);
PAINT WHITE (-1450 3925);
DISPLAY INVISIBLE (-1450 3925);
FORCEPROP 1 LAST PART_NUMBER TMP_QCH03306JB04
J 0
(-1450 3675);
DISPLAY 0.808511 (-1450 3675);
PAINT SKYBLUE (-1450 3675);
DISPLAY INVISIBLE (-1450 3675);
FORCEADD GND..1
(-1500 3450);
FORCEPROP 3 LASTPIN (-1500 3500) SIG_NAME GND\g
J 0
(-1490 3510);
DISPLAY 0.659574 (-1490 3510);
PAINT MONO (-1490 3510);
DISPLAY INVISIBLE (-1490 3510);
FORCEPROP 2 LAST CDS_LIB pure_quanta_power
J 0
(-1500 3450);
DISPLAY INVISIBLE (-1500 3450);
FORCEPROP 1 LAST SIZE 1B
J 0
(-1425 3400);
DISPLAY 0.872340 (-1425 3400);
PAINT GREEN (-1425 3400);
DISPLAY INVISIBLE (-1425 3400);
FORCEPROP 1 LAST HDL_POWER GND
J 0
(-1500 3600);
DISPLAY 0.872340 (-1500 3600);
PAINT GREEN (-1500 3600);
DISPLAY INVISIBLE (-1500 3600);
FORCEPROP 1 LAST PATH I26
J 0
(-1425 3450);
DISPLAY 0.872340 (-1425 3450);
PAINT AQUA (-1425 3450);
DISPLAY INVISIBLE (-1425 3450);
FORCEADD GND..1
(-2700 3500);
FORCEPROP 3 LASTPIN (-2700 3550) SIG_NAME GND\g
J 0
(-2690 3560);
DISPLAY 0.659574 (-2690 3560);
PAINT MONO (-2690 3560);
DISPLAY INVISIBLE (-2690 3560);
FORCEPROP 1 LAST SIZE 1B
J 0
(-2625 3450);
DISPLAY 0.872340 (-2625 3450);
PAINT GREEN (-2625 3450);
DISPLAY INVISIBLE (-2625 3450);
FORCEPROP 2 LAST CDS_LIB pure_quanta_power
J 0
(-2700 3500);
PAINT MONO (-2700 3500);
DISPLAY INVISIBLE (-2700 3500);
FORCEPROP 1 LAST HDL_POWER GND
J 0
(-2700 3650);
DISPLAY 0.872340 (-2700 3650);
PAINT GREEN (-2700 3650);
DISPLAY INVISIBLE (-2700 3650);
FORCEPROP 1 LAST PATH I27
J 0
(-2625 3500);
DISPLAY 0.872340 (-2625 3500);
PAINT AQUA (-2625 3500);
DISPLAY INVISIBLE (-2625 3500);
FORCEADD UNIVERSAL_POWER..1
(-2725 2950);
FORCEPROP 3 LASTPIN (-2725 2900) SIG_NAME PVDD18_S5_P0\g
J 0
(-2715 2910);
DISPLAY 0.659574 (-2715 2910);
PAINT MONO (-2715 2910);
DISPLAY INVISIBLE (-2715 2910);
FORCEPROP 1 LAST HDL_POWER PVDD18_S5_P0
J 1
(-2725 3000);
DISPLAY 0.489362 (-2725 3000);
PAINT GREEN (-2725 3000);
FORCEPROP 2 LAST CDS_LIB pure_quanta_power
J 0
(-2725 2950);
PAINT MONO (-2725 2950);
DISPLAY INVISIBLE (-2725 2950);
FORCEPROP 1 LAST PATH I28
J 0
(-2675 2975);
DISPLAY 0.872340 (-2675 2975);
PAINT AQUA (-2675 2975);
DISPLAY INVISIBLE (-2675 2975);
FORCEADD Q_CAP..1
(-2650 2650);
FORCEPROP 1 LAST LOCATION C1508
J 0
(-2550 2800);
DISPLAY 0.489362 (-2550 2800);
PAINT SKYBLUE (-2550 2800);
FORCEPROP 2 LAST $SEC 1
J 0
(-2600 2850);
PAINT MONO (-2600 2850);
DISPLAY INVISIBLE (-2600 2850);
FORCEPROP 2 LAST CDS_SEC 1
J 0
(-2600 2850);
PAINT MONO (-2600 2850);
DISPLAY INVISIBLE (-2600 2850);
FORCEPROP 1 LASTPIN (-2650 2750) $PN 1
J 0
(-2640 2730);
DISPLAY 0.489362 (-2640 2730);
PAINT GREEN (-2640 2730);
FORCEPROP 1 LASTPIN (-2650 2550) $PN 2
J 0
(-2640 2530);
DISPLAY 0.489362 (-2640 2530);
PAINT GREEN (-2640 2530);
FORCEPROP 1 LAST PACK_TYPE C0402
J 0
(-2550 2500);
DISPLAY 0.489362 (-2550 2500);
PAINT SKYBLUE (-2550 2500);
FORCEPROP 1 LAST VOLTAGE 16V
J 0
(-2550 2700);
DISPLAY 0.489362 (-2550 2700);
PAINT SKYBLUE (-2550 2700);
FORCEPROP 1 LAST VALUE 0.1UF
J 0
(-2550 2750);
DISPLAY 0.489362 (-2550 2750);
PAINT SKYBLUE (-2550 2750);
FORCEPROP 1 LAST TOLERANCE 10%
J 0
(-2550 2650);
DISPLAY 0.489362 (-2550 2650);
PAINT SKYBLUE (-2550 2650);
FORCEPROP 1 LAST MATERIAL X7R
J 0
(-2550 2600);
DISPLAY 0.489362 (-2550 2600);
PAINT SKYBLUE (-2550 2600);
FORCEPROP 2 LAST CDS_LIB pure_quanta
J 0
(-2650 2650);
DISPLAY INVISIBLE (-2650 2650);
FORCEPROP 1 LAST PATH I29
J 0
(-2600 2800);
DISPLAY 0.978723 (-2600 2800);
PAINT WHITE (-2600 2800);
DISPLAY INVISIBLE (-2600 2800);
FORCEPROP 1 LAST PART_NUMBER CH4103K1B08
J 0
(-2550 2550);
DISPLAY 0.489362 (-2550 2550);
PAINT SKYBLUE (-2550 2550);
DISPLAY INVISIBLE (-2550 2550);
FORCEADD OFFPAGE..2
(-525 4225);
FORCEPROP 2 LAST $XR0 173 
J 0
(-336 4225);
DISPLAY 0.638298 (-336 4225);
PAINT MONO (-336 4225);
FORCEPROP 2 LAST CDS_LIB standard
J 0
(-525 4225);
PAINT MONO (-525 4225);
DISPLAY INVISIBLE (-525 4225);
FORCEPROP 1 LAST OFFPAGE TRUE
J 0
(-200 4100);
DISPLAY 0.872340 (-200 4100);
PAINT GREEN (-200 4100);
DISPLAY INVISIBLE (-200 4100);
FORCEPROP 1 LAST COMMENT_BODY TRUE
J 0
(-570 4130);
DISPLAY 0.872340 (-570 4130);
PAINT GREEN (-570 4130);
DISPLAY INVISIBLE (-570 4130);
FORCEPROP 2 LAST PATH I3
J 0
(-325 4275);
DISPLAY 1.021277 (-325 4275);
DISPLAY INVISIBLE (-325 4275);
FORCEADD GND..1
(-2650 2475);
FORCEPROP 3 LASTPIN (-2650 2525) SIG_NAME GND\g
J 0
(-2640 2535);
DISPLAY 0.659574 (-2640 2535);
PAINT MONO (-2640 2535);
DISPLAY INVISIBLE (-2640 2535);
FORCEPROP 2 LAST CDS_LIB pure_quanta_power
J 0
(-2650 2475);
DISPLAY INVISIBLE (-2650 2475);
FORCEPROP 1 LAST SIZE 1B
J 0
(-2575 2425);
DISPLAY 0.872340 (-2575 2425);
PAINT GREEN (-2575 2425);
DISPLAY INVISIBLE (-2575 2425);
FORCEPROP 1 LAST HDL_POWER GND
J 0
(-2650 2625);
DISPLAY 0.872340 (-2650 2625);
PAINT GREEN (-2650 2625);
DISPLAY INVISIBLE (-2650 2625);
FORCEPROP 1 LAST PATH I30
J 0
(-2575 2475);
DISPLAY 0.872340 (-2575 2475);
PAINT AQUA (-2575 2475);
DISPLAY INVISIBLE (-2575 2475);
FORCEADD SN74AVC4T774PWR..1
(-3225 4075);
FORCEPROP 1 LAST LOCATION U149
J 0
(-3472 4640);
DISPLAY 0.489362 (-3472 4640);
PAINT SKYBLUE (-3472 4640);
FORCEPROP 0 LAST $SEC 1
J 0
(-3450 4775);
PAINT MONO (-3450 4775);
DISPLAY INVISIBLE (-3450 4775);
FORCEPROP 0 LAST CDS_SEC 1
J 0
(-3450 4775);
PAINT MONO (-3450 4775);
DISPLAY INVISIBLE (-3450 4775);
FORCEPROP 0 LASTPIN (-3625 4225) $PN 3
J 2
(-3635 4235);
DISPLAY 0.489362 (-3635 4235);
PAINT MONO (-3635 4235);
FORCEPROP 0 LASTPIN (-3625 4175) $PN 4
J 2
(-3635 4185);
DISPLAY 0.489362 (-3635 4185);
PAINT MONO (-3635 4185);
FORCEPROP 0 LASTPIN (-3625 4125) $PN 5
J 2
(-3635 4135);
DISPLAY 0.489362 (-3635 4135);
PAINT MONO (-3635 4135);
FORCEPROP 0 LASTPIN (-3625 4075) $PN 6
J 2
(-3635 4085);
DISPLAY 0.489362 (-3635 4085);
PAINT MONO (-3635 4085);
FORCEPROP 0 LASTPIN (-2825 4225) $PN 14
J 0
(-2815 4235);
DISPLAY 0.489362 (-2815 4235);
PAINT MONO (-2815 4235);
FORCEPROP 0 LASTPIN (-2825 4175) $PN 13
J 0
(-2815 4185);
DISPLAY 0.489362 (-2815 4185);
PAINT MONO (-2815 4185);
FORCEPROP 0 LASTPIN (-2825 4125) $PN 12
J 0
(-2815 4135);
DISPLAY 0.489362 (-2815 4135);
PAINT MONO (-2815 4135);
FORCEPROP 0 LASTPIN (-2825 4075) $PN 11
J 0
(-2815 4085);
DISPLAY 0.489362 (-2815 4085);
PAINT MONO (-2815 4085);
FORCEPROP 0 LASTPIN (-3625 3925) $PN 1
J 2
(-3635 3935);
DISPLAY 0.489362 (-3635 3935);
PAINT MONO (-3635 3935);
FORCEPROP 0 LASTPIN (-3625 3875) $PN 2
J 2
(-3635 3885);
DISPLAY 0.489362 (-3635 3885);
PAINT MONO (-3635 3885);
FORCEPROP 0 LASTPIN (-3625 3825) $PN 7
J 2
(-3635 3835);
DISPLAY 0.489362 (-3635 3835);
PAINT MONO (-3635 3835);
FORCEPROP 0 LASTPIN (-3625 3775) $PN 8
J 2
(-3635 3785);
DISPLAY 0.489362 (-3635 3785);
PAINT MONO (-3635 3785);
FORCEPROP 0 LASTPIN (-2825 3675) $PN 10
J 0
(-2815 3685);
DISPLAY 0.489362 (-2815 3685);
PAINT MONO (-2815 3685);
FORCEPROP 0 LASTPIN (-3625 3725) $PN 9
J 2
(-3635 3735);
DISPLAY 0.489362 (-3635 3735);
PAINT MONO (-3635 3735);
FORCEPROP 0 LASTPIN (-3625 4425) $PN 16
J 2
(-3635 4435);
DISPLAY 0.489362 (-3635 4435);
PAINT MONO (-3635 4435);
FORCEPROP 0 LASTPIN (-2825 4425) $PN 15
J 0
(-2815 4435);
DISPLAY 0.489362 (-2815 4435);
PAINT MONO (-2815 4435);
FORCEPROP 2 LAST PART_TYPE SMLF
J 0
(-3475 4775);
PAINT MONO (-3475 4775);
FORCEPROP 2 LAST VALUE SN74AVC4T774PWR
J 0
(-3475 4700);
DISPLAY 0.489362 (-3475 4700);
PAINT SKYBLUE (-3475 4700);
FORCEPROP 1 LAST MATERIAL IC
J 0
(-3472 4528);
DISPLAY 0.489362 (-3472 4528);
PAINT SKYBLUE (-3472 4528);
FORCEPROP 1 LAST CDS_LMAN_SYM_OUTLINE -250,450,250,-450
J 0
(-3225 4075);
DISPLAY 0.468085 (-3225 4075);
PAINT GREEN (-3225 4075);
DISPLAY INVISIBLE (-3225 4075);
FORCEPROP 1 LAST NEEDS_NO_SIZE TRUE
J 0
(-3225 4075);
DISPLAY 0.723404 (-3225 4075);
PAINT GREEN (-3225 4075);
DISPLAY INVISIBLE (-3225 4075);
FORCEPROP 2 LAST CDS_LIB pure_quanta
J 0
(-3225 4075);
PAINT MONO (-3225 4075);
DISPLAY INVISIBLE (-3225 4075);
FORCEPROP 1 LAST PATH I31
J 0
(-3225 4075);
DISPLAY 0.723404 (-3225 4075);
PAINT GREEN (-3225 4075);
DISPLAY INVISIBLE (-3225 4075);
FORCEPROP 1 LAST PART_NUMBER AL04T774K00
J 0
(-3472 4583);
DISPLAY 0.489362 (-3472 4583);
PAINT SKYBLUE (-3472 4583);
DISPLAY INVISIBLE (-3472 4583);
FORCEADD UNIVERSAL_POWER..1
(-3750 2675);
FORCEPROP 3 LASTPIN (-3750 2625) SIG_NAME P3V3_AUX\g
J 0
(-3740 2635);
DISPLAY 0.659574 (-3740 2635);
PAINT MONO (-3740 2635);
DISPLAY INVISIBLE (-3740 2635);
FORCEPROP 1 LAST HDL_POWER P3V3_AUX
J 1
(-3750 2725);
DISPLAY 0.489362 (-3750 2725);
PAINT GREEN (-3750 2725);
FORCEPROP 2 LAST CDS_LIB pure_quanta_power
J 0
(-3750 2675);
PAINT MONO (-3750 2675);
DISPLAY INVISIBLE (-3750 2675);
FORCEPROP 1 LAST PATH I32
J 0
(-3700 2700);
DISPLAY 0.872340 (-3700 2700);
PAINT AQUA (-3700 2700);
DISPLAY INVISIBLE (-3700 2700);
FORCEADD GND..1
(-2725 1350);
FORCEPROP 3 LASTPIN (-2725 1400) SIG_NAME GND\g
J 0
(-2715 1410);
DISPLAY 0.659574 (-2715 1410);
PAINT MONO (-2715 1410);
DISPLAY INVISIBLE (-2715 1410);
FORCEPROP 2 LAST CDS_LIB pure_quanta_power
J 0
(-2725 1350);
PAINT MONO (-2725 1350);
DISPLAY INVISIBLE (-2725 1350);
FORCEPROP 1 LAST SIZE 1B
J 0
(-2650 1300);
DISPLAY 0.872340 (-2650 1300);
PAINT GREEN (-2650 1300);
DISPLAY INVISIBLE (-2650 1300);
FORCEPROP 1 LAST HDL_POWER GND
J 0
(-2725 1500);
DISPLAY 0.872340 (-2725 1500);
PAINT GREEN (-2725 1500);
DISPLAY INVISIBLE (-2725 1500);
FORCEPROP 1 LAST PATH I33
J 0
(-2650 1350);
DISPLAY 0.872340 (-2650 1350);
PAINT AQUA (-2650 1350);
DISPLAY INVISIBLE (-2650 1350);
FORCEADD SN74AVC4T774PWR..1
(-3250 1925);
FORCEPROP 1 LAST LOCATION U148
J 0
(-3497 2490);
DISPLAY 0.489362 (-3497 2490);
PAINT SKYBLUE (-3497 2490);
FORCEPROP 0 LAST $SEC 1
J 0
(-3475 2625);
PAINT MONO (-3475 2625);
DISPLAY INVISIBLE (-3475 2625);
FORCEPROP 0 LAST CDS_SEC 1
J 0
(-3475 2625);
PAINT MONO (-3475 2625);
DISPLAY INVISIBLE (-3475 2625);
FORCEPROP 0 LASTPIN (-3650 2075) $PN 3
J 2
(-3660 2085);
DISPLAY 0.489362 (-3660 2085);
PAINT MONO (-3660 2085);
FORCEPROP 0 LASTPIN (-3650 2025) $PN 4
J 2
(-3660 2035);
DISPLAY 0.489362 (-3660 2035);
PAINT MONO (-3660 2035);
FORCEPROP 0 LASTPIN (-3650 1975) $PN 5
J 2
(-3660 1985);
DISPLAY 0.489362 (-3660 1985);
PAINT MONO (-3660 1985);
FORCEPROP 0 LASTPIN (-3650 1925) $PN 6
J 2
(-3660 1935);
DISPLAY 0.489362 (-3660 1935);
PAINT MONO (-3660 1935);
FORCEPROP 0 LASTPIN (-2850 2075) $PN 14
J 0
(-2840 2085);
DISPLAY 0.489362 (-2840 2085);
PAINT MONO (-2840 2085);
FORCEPROP 0 LASTPIN (-2850 2025) $PN 13
J 0
(-2840 2035);
DISPLAY 0.489362 (-2840 2035);
PAINT MONO (-2840 2035);
FORCEPROP 0 LASTPIN (-2850 1975) $PN 12
J 0
(-2840 1985);
DISPLAY 0.489362 (-2840 1985);
PAINT MONO (-2840 1985);
FORCEPROP 0 LASTPIN (-2850 1925) $PN 11
J 0
(-2840 1935);
DISPLAY 0.489362 (-2840 1935);
PAINT MONO (-2840 1935);
FORCEPROP 0 LASTPIN (-3650 1775) $PN 1
J 2
(-3660 1785);
DISPLAY 0.489362 (-3660 1785);
PAINT MONO (-3660 1785);
FORCEPROP 0 LASTPIN (-3650 1725) $PN 2
J 2
(-3660 1735);
DISPLAY 0.489362 (-3660 1735);
PAINT MONO (-3660 1735);
FORCEPROP 0 LASTPIN (-3650 1675) $PN 7
J 2
(-3660 1685);
DISPLAY 0.489362 (-3660 1685);
PAINT MONO (-3660 1685);
FORCEPROP 0 LASTPIN (-3650 1625) $PN 8
J 2
(-3660 1635);
DISPLAY 0.489362 (-3660 1635);
PAINT MONO (-3660 1635);
FORCEPROP 0 LASTPIN (-2850 1525) $PN 10
J 0
(-2840 1535);
DISPLAY 0.489362 (-2840 1535);
PAINT MONO (-2840 1535);
FORCEPROP 0 LASTPIN (-3650 1575) $PN 9
J 2
(-3660 1585);
DISPLAY 0.489362 (-3660 1585);
PAINT MONO (-3660 1585);
FORCEPROP 0 LASTPIN (-3650 2275) $PN 16
J 2
(-3660 2285);
DISPLAY 0.489362 (-3660 2285);
PAINT MONO (-3660 2285);
FORCEPROP 0 LASTPIN (-2850 2275) $PN 15
J 0
(-2840 2285);
DISPLAY 0.489362 (-2840 2285);
PAINT MONO (-2840 2285);
FORCEPROP 2 LAST VALUE SN74AVC4T774PWR
J 0
(-3500 2550);
DISPLAY 0.489362 (-3500 2550);
PAINT SKYBLUE (-3500 2550);
FORCEPROP 1 LAST MATERIAL IC
J 0
(-3497 2378);
DISPLAY 0.489362 (-3497 2378);
PAINT SKYBLUE (-3497 2378);
FORCEPROP 2 LAST PART_TYPE SMLF
J 0
(-3500 2625);
PAINT MONO (-3500 2625);
FORCEPROP 1 LAST NEEDS_NO_SIZE TRUE
J 0
(-3250 1925);
DISPLAY 0.723404 (-3250 1925);
PAINT GREEN (-3250 1925);
DISPLAY INVISIBLE (-3250 1925);
FORCEPROP 2 LAST CDS_LIB pure_quanta
J 0
(-3250 1925);
PAINT MONO (-3250 1925);
DISPLAY INVISIBLE (-3250 1925);
FORCEPROP 1 LAST CDS_LMAN_SYM_OUTLINE -250,450,250,-450
J 0
(-3250 1925);
DISPLAY 0.468085 (-3250 1925);
PAINT GREEN (-3250 1925);
DISPLAY INVISIBLE (-3250 1925);
FORCEPROP 1 LAST PATH I34
J 0
(-3250 1925);
DISPLAY 0.723404 (-3250 1925);
PAINT GREEN (-3250 1925);
DISPLAY INVISIBLE (-3250 1925);
FORCEPROP 1 LAST PART_NUMBER AL04T774K00
J 0
(-3497 2433);
DISPLAY 0.489362 (-3497 2433);
PAINT SKYBLUE (-3497 2433);
DISPLAY INVISIBLE (-3497 2433);
FORCEADD OFFPAGE..2
(-525 4175);
FORCEPROP 2 LAST $XR0 173 
J 0
(-336 4175);
DISPLAY 0.638298 (-336 4175);
PAINT MONO (-336 4175);
FORCEPROP 2 LAST CDS_LIB standard
J 0
(-525 4175);
PAINT MONO (-525 4175);
DISPLAY INVISIBLE (-525 4175);
FORCEPROP 1 LAST OFFPAGE TRUE
J 0
(-200 4050);
DISPLAY 0.872340 (-200 4050);
PAINT GREEN (-200 4050);
DISPLAY INVISIBLE (-200 4050);
FORCEPROP 1 LAST COMMENT_BODY TRUE
J 0
(-570 4080);
DISPLAY 0.872340 (-570 4080);
PAINT GREEN (-570 4080);
DISPLAY INVISIBLE (-570 4080);
FORCEPROP 2 LAST PATH I4
J 0
(-325 4225);
DISPLAY 1.021277 (-325 4225);
DISPLAY INVISIBLE (-325 4225);
FORCEADD Q_CAP..1
(-3975 4550);
FORCEPROP 1 LAST LOCATION C1507
J 0
(-4125 4675);
DISPLAY 0.489362 (-4125 4675);
PAINT SKYBLUE (-4125 4675);
FORCEPROP 2 LAST $SEC 1
J 0
(-3925 4750);
PAINT MONO (-3925 4750);
DISPLAY INVISIBLE (-3925 4750);
FORCEPROP 2 LAST CDS_SEC 1
J 0
(-3925 4750);
PAINT MONO (-3925 4750);
DISPLAY INVISIBLE (-3925 4750);
FORCEPROP 1 LASTPIN (-3975 4650) $PN 1
J 0
(-3965 4630);
DISPLAY 0.489362 (-3965 4630);
PAINT GREEN (-3965 4630);
FORCEPROP 1 LASTPIN (-3975 4450) $PN 2
J 0
(-3965 4430);
DISPLAY 0.489362 (-3965 4430);
PAINT GREEN (-3965 4430);
FORCEPROP 1 LAST VALUE 0.1UF
J 0
(-4150 4625);
DISPLAY 0.489362 (-4150 4625);
PAINT SKYBLUE (-4150 4625);
FORCEPROP 1 LAST PACK_TYPE C0402
J 0
(-4150 4375);
DISPLAY 0.489362 (-4150 4375);
PAINT SKYBLUE (-4150 4375);
FORCEPROP 1 LAST VOLTAGE 16V
J 0
(-4100 4575);
DISPLAY 0.489362 (-4100 4575);
PAINT SKYBLUE (-4100 4575);
FORCEPROP 1 LAST TOLERANCE 10%
J 0
(-4100 4525);
DISPLAY 0.489362 (-4100 4525);
PAINT SKYBLUE (-4100 4525);
FORCEPROP 1 LAST MATERIAL X7R
J 0
(-4100 4475);
DISPLAY 0.489362 (-4100 4475);
PAINT SKYBLUE (-4100 4475);
FORCEPROP 2 LAST CDS_LIB pure_quanta
J 0
(-3975 4550);
DISPLAY INVISIBLE (-3975 4550);
FORCEPROP 1 LAST PATH I41
J 0
(-3925 4700);
DISPLAY 0.978723 (-3925 4700);
PAINT WHITE (-3925 4700);
DISPLAY INVISIBLE (-3925 4700);
FORCEPROP 1 LAST PART_NUMBER CH4103K1B08
J 0
(-4325 4425);
DISPLAY 0.489362 (-4325 4425);
PAINT SKYBLUE (-4325 4425);
DISPLAY INVISIBLE (-4325 4425);
FORCEADD GND..1
(-3975 4375);
FORCEPROP 3 LASTPIN (-3975 4425) SIG_NAME GND\g
J 0
(-3965 4435);
DISPLAY 0.659574 (-3965 4435);
PAINT MONO (-3965 4435);
DISPLAY INVISIBLE (-3965 4435);
FORCEPROP 2 LAST CDS_LIB pure_quanta_power
J 0
(-3975 4375);
DISPLAY INVISIBLE (-3975 4375);
FORCEPROP 1 LAST SIZE 1B
J 0
(-3900 4325);
DISPLAY 0.872340 (-3900 4325);
PAINT GREEN (-3900 4325);
DISPLAY INVISIBLE (-3900 4325);
FORCEPROP 1 LAST HDL_POWER GND
J 0
(-3975 4525);
DISPLAY 0.872340 (-3975 4525);
PAINT GREEN (-3975 4525);
DISPLAY INVISIBLE (-3975 4525);
FORCEPROP 1 LAST PATH I42
J 0
(-3900 4375);
DISPLAY 0.872340 (-3900 4375);
PAINT AQUA (-3900 4375);
DISPLAY INVISIBLE (-3900 4375);
FORCEADD OFFPAGE..1
(-4375 4225);
FORCEPROP 2 LAST $XR0 172 
J 0
(-4627 4225);
DISPLAY 0.638298 (-4627 4225);
PAINT MONO (-4627 4225);
FORCEPROP 2 LAST CDS_LIB standard
J 0
(-4375 4225);
PAINT MONO (-4375 4225);
DISPLAY INVISIBLE (-4375 4225);
FORCEPROP 1 LAST OFFPAGE TRUE
J 0
(-4050 4100);
DISPLAY 0.872340 (-4050 4100);
PAINT GREEN (-4050 4100);
DISPLAY INVISIBLE (-4050 4100);
FORCEPROP 1 LAST COMMENT_BODY TRUE
J 0
(-4250 4125);
DISPLAY 0.872340 (-4250 4125);
PAINT GREEN (-4250 4125);
DISPLAY INVISIBLE (-4250 4125);
FORCEPROP 2 LAST PATH I43
J 0
(-4575 4275);
DISPLAY 1.021277 (-4575 4275);
DISPLAY INVISIBLE (-4575 4275);
FORCEADD OFFPAGE..1
(-4375 4125);
FORCEPROP 2 LAST $XR0 172 
J 0
(-4627 4125);
DISPLAY 0.638298 (-4627 4125);
PAINT MONO (-4627 4125);
FORCEPROP 2 LAST CDS_LIB standard
J 0
(-4375 4125);
PAINT MONO (-4375 4125);
DISPLAY INVISIBLE (-4375 4125);
FORCEPROP 1 LAST OFFPAGE TRUE
J 0
(-4050 4000);
DISPLAY 0.872340 (-4050 4000);
PAINT GREEN (-4050 4000);
DISPLAY INVISIBLE (-4050 4000);
FORCEPROP 1 LAST COMMENT_BODY TRUE
J 0
(-4250 4025);
DISPLAY 0.872340 (-4250 4025);
PAINT GREEN (-4250 4025);
DISPLAY INVISIBLE (-4250 4025);
FORCEPROP 2 LAST PATH I44
J 0
(-4575 4175);
DISPLAY 1.021277 (-4575 4175);
DISPLAY INVISIBLE (-4575 4175);
FORCEADD OFFPAGE..1
(-4375 4175);
FORCEPROP 2 LAST $XR0 172 
J 0
(-4627 4175);
DISPLAY 0.638298 (-4627 4175);
PAINT MONO (-4627 4175);
FORCEPROP 2 LAST CDS_LIB standard
J 0
(-4375 4175);
PAINT MONO (-4375 4175);
DISPLAY INVISIBLE (-4375 4175);
FORCEPROP 1 LAST OFFPAGE TRUE
J 0
(-4050 4050);
DISPLAY 0.872340 (-4050 4050);
PAINT GREEN (-4050 4050);
DISPLAY INVISIBLE (-4050 4050);
FORCEPROP 1 LAST COMMENT_BODY TRUE
J 0
(-4250 4075);
DISPLAY 0.872340 (-4250 4075);
PAINT GREEN (-4250 4075);
DISPLAY INVISIBLE (-4250 4075);
FORCEPROP 2 LAST PATH I45
J 0
(-4575 4225);
DISPLAY 1.021277 (-4575 4225);
DISPLAY INVISIBLE (-4575 4225);
FORCEADD OFFPAGE..1
(-4375 4075);
FORCEPROP 2 LAST $XR0 172 
J 0
(-4627 4075);
DISPLAY 0.638298 (-4627 4075);
PAINT MONO (-4627 4075);
FORCEPROP 2 LAST CDS_LIB standard
J 0
(-4375 4075);
PAINT MONO (-4375 4075);
DISPLAY INVISIBLE (-4375 4075);
FORCEPROP 1 LAST OFFPAGE TRUE
J 0
(-4050 3950);
DISPLAY 0.872340 (-4050 3950);
PAINT GREEN (-4050 3950);
DISPLAY INVISIBLE (-4050 3950);
FORCEPROP 1 LAST COMMENT_BODY TRUE
J 0
(-4250 3975);
DISPLAY 0.872340 (-4250 3975);
PAINT GREEN (-4250 3975);
DISPLAY INVISIBLE (-4250 3975);
FORCEPROP 2 LAST PATH I46
J 0
(-4575 4125);
DISPLAY 1.021277 (-4575 4125);
DISPLAY INVISIBLE (-4575 4125);
FORCEADD OFFPAGE..2
(-525 4075);
FORCEPROP 2 LAST $XR0 173 
J 0
(-336 4075);
DISPLAY 0.638298 (-336 4075);
PAINT MONO (-336 4075);
FORCEPROP 2 LAST CDS_LIB standard
J 0
(-525 4075);
PAINT MONO (-525 4075);
DISPLAY INVISIBLE (-525 4075);
FORCEPROP 1 LAST OFFPAGE TRUE
J 0
(-200 3950);
DISPLAY 0.872340 (-200 3950);
PAINT GREEN (-200 3950);
DISPLAY INVISIBLE (-200 3950);
FORCEPROP 1 LAST COMMENT_BODY TRUE
J 0
(-570 3980);
DISPLAY 0.872340 (-570 3980);
PAINT GREEN (-570 3980);
DISPLAY INVISIBLE (-570 3980);
FORCEPROP 2 LAST PATH I5
J 0
(-325 4125);
DISPLAY 1.021277 (-325 4125);
DISPLAY INVISIBLE (-325 4125);
FORCEADD OFFPAGE..2
(-5100 4075);
FORCEPROP 2 LAST $XR0 173 
J 0
(-4911 4075);
DISPLAY 0.638298 (-4911 4075);
PAINT MONO (-4911 4075);
FORCEPROP 2 LAST CDS_LIB standard
J 0
(-5100 4075);
PAINT MONO (-5100 4075);
DISPLAY INVISIBLE (-5100 4075);
FORCEPROP 1 LAST OFFPAGE TRUE
J 0
(-4775 3950);
DISPLAY 0.872340 (-4775 3950);
PAINT GREEN (-4775 3950);
DISPLAY INVISIBLE (-4775 3950);
FORCEPROP 1 LAST COMMENT_BODY TRUE
J 0
(-5145 3980);
DISPLAY 0.872340 (-5145 3980);
PAINT GREEN (-5145 3980);
DISPLAY INVISIBLE (-5145 3980);
FORCEPROP 2 LAST PATH I51
J 0
(-4900 4125);
DISPLAY 1.021277 (-4900 4125);
DISPLAY INVISIBLE (-4900 4125);
FORCEADD Q_RES..1
(-5675 4075);
FORCEPROP 1 LAST LOCATION R1625
J 0
(-5900 4075);
DISPLAY 0.489362 (-5900 4075);
PAINT SKYBLUE (-5900 4075);
FORCEPROP 0 LAST $SEC 1
J 0
(-5525 4125);
PAINT MONO (-5525 4125);
DISPLAY INVISIBLE (-5525 4125);
FORCEPROP 0 LAST CDS_SEC 1
J 0
(-5525 4125);
PAINT MONO (-5525 4125);
DISPLAY INVISIBLE (-5525 4125);
FORCEPROP 1 LASTPIN (-5775 4075) $PN 1
J 0
(-5763 4087);
DISPLAY 0.489362 (-5763 4087);
PAINT GREEN (-5763 4087);
FORCEPROP 1 LASTPIN (-5575 4075) $PN 2
J 0
(-5613 4087);
DISPLAY 0.489362 (-5613 4087);
PAINT GREEN (-5613 4087);
FORCEPROP 1 LAST VALUE 0
J 2
(-5525 4075);
DISPLAY 0.489362 (-5525 4075);
PAINT SKYBLUE (-5525 4075);
FORCEPROP 1 LAST PACK_TYPE 0402LF
J 0
(-5425 3925);
DISPLAY 0.978723 (-5425 3925);
PAINT SKYBLUE (-5425 3925);
DISPLAY INVISIBLE (-5425 3925);
FORCEPROP 1 LAST TOLERANCE 5%
J 0
(-5675 3975);
DISPLAY 0.978723 (-5675 3975);
PAINT SKYBLUE (-5675 3975);
DISPLAY INVISIBLE (-5675 3975);
FORCEPROP 1 LAST MATERIAL CHIP
J 0
(-5450 4075);
DISPLAY 0.617021 (-5450 4075);
PAINT SKYBLUE (-5450 4075);
DISPLAY INVISIBLE (-5450 4075);
FORCEPROP 1 LAST WATTAGE 1/16W
J 2
(-5700 3925);
DISPLAY 0.978723 (-5700 3925);
PAINT SKYBLUE (-5700 3925);
DISPLAY INVISIBLE (-5700 3925);
FORCEPROP 2 LAST CDS_LIB pure_quanta
J 0
(-5675 4075);
PAINT MONO (-5675 4075);
DISPLAY INVISIBLE (-5675 4075);
FORCEPROP 1 LAST PATH I53
J 0
(-5725 4225);
DISPLAY 0.978723 (-5725 4225);
PAINT WHITE (-5725 4225);
DISPLAY INVISIBLE (-5725 4225);
FORCEPROP 1 LAST PART_NUMBER CS00002JB13
J 0
(-5725 4175);
DISPLAY 0.978723 (-5725 4175);
PAINT SKYBLUE (-5725 4175);
DISPLAY INVISIBLE (-5725 4175);
FORCEADD UNIVERSAL_POWER..1
(-6475 4900);
FORCEPROP 3 LASTPIN (-6475 4850) SIG_NAME PVDD18_S5_P0\g
J 0
(-6465 4860);
DISPLAY 0.659574 (-6465 4860);
PAINT MONO (-6465 4860);
DISPLAY INVISIBLE (-6465 4860);
FORCEPROP 1 LAST HDL_POWER PVDD18_S5_P0
J 1
(-6450 4950);
DISPLAY 0.489362 (-6450 4950);
PAINT GREEN (-6450 4950);
FORCEPROP 2 LAST CDS_LIB pure_quanta_power
J 0
(-6475 4900);
PAINT MONO (-6475 4900);
DISPLAY INVISIBLE (-6475 4900);
FORCEPROP 1 LAST PATH I54
J 0
(-6425 4925);
DISPLAY 0.872340 (-6425 4925);
PAINT AQUA (-6425 4925);
DISPLAY INVISIBLE (-6425 4925);
FORCEADD GND..1
(-6350 4400);
FORCEPROP 3 LASTPIN (-6350 4450) SIG_NAME GND\g
J 0
(-6340 4460);
DISPLAY 0.659574 (-6340 4460);
PAINT MONO (-6340 4460);
DISPLAY INVISIBLE (-6340 4460);
FORCEPROP 2 LAST CDS_LIB pure_quanta_power
J 0
(-6350 4400);
DISPLAY INVISIBLE (-6350 4400);
FORCEPROP 1 LAST SIZE 1B
J 0
(-6275 4350);
DISPLAY 0.872340 (-6275 4350);
PAINT GREEN (-6275 4350);
DISPLAY INVISIBLE (-6275 4350);
FORCEPROP 1 LAST HDL_POWER GND
J 0
(-6350 4550);
DISPLAY 0.872340 (-6350 4550);
PAINT GREEN (-6350 4550);
DISPLAY INVISIBLE (-6350 4550);
FORCEPROP 1 LAST PATH I55
J 0
(-6275 4400);
DISPLAY 0.872340 (-6275 4400);
PAINT AQUA (-6275 4400);
DISPLAY INVISIBLE (-6275 4400);
FORCEADD Q_CAP..1
(-6350 4625);
FORCEPROP 1 LAST LOCATION C1504
J 0
(-6250 4775);
DISPLAY 0.489362 (-6250 4775);
PAINT SKYBLUE (-6250 4775);
FORCEPROP 2 LAST $SEC 1
J 0
(-6300 4825);
PAINT MONO (-6300 4825);
DISPLAY INVISIBLE (-6300 4825);
FORCEPROP 2 LAST CDS_SEC 1
J 0
(-6300 4825);
PAINT MONO (-6300 4825);
DISPLAY INVISIBLE (-6300 4825);
FORCEPROP 1 LASTPIN (-6350 4725) $PN 1
J 0
(-6340 4705);
DISPLAY 0.489362 (-6340 4705);
PAINT GREEN (-6340 4705);
FORCEPROP 1 LASTPIN (-6350 4525) $PN 2
J 0
(-6340 4505);
DISPLAY 0.489362 (-6340 4505);
PAINT GREEN (-6340 4505);
FORCEPROP 1 LAST PACK_TYPE C0402
J 0
(-6250 4475);
DISPLAY 0.489362 (-6250 4475);
PAINT SKYBLUE (-6250 4475);
FORCEPROP 1 LAST VOLTAGE 16V
J 0
(-6250 4675);
DISPLAY 0.489362 (-6250 4675);
PAINT SKYBLUE (-6250 4675);
FORCEPROP 1 LAST VALUE 0.1UF
J 0
(-6250 4725);
DISPLAY 0.489362 (-6250 4725);
PAINT SKYBLUE (-6250 4725);
FORCEPROP 1 LAST TOLERANCE 10%
J 0
(-6250 4625);
DISPLAY 0.489362 (-6250 4625);
PAINT SKYBLUE (-6250 4625);
FORCEPROP 1 LAST MATERIAL X7R
J 0
(-6250 4575);
DISPLAY 0.489362 (-6250 4575);
PAINT SKYBLUE (-6250 4575);
FORCEPROP 2 LAST CDS_LIB pure_quanta
J 0
(-6350 4625);
DISPLAY INVISIBLE (-6350 4625);
FORCEPROP 1 LAST PATH I56
J 0
(-6300 4775);
DISPLAY 0.978723 (-6300 4775);
PAINT WHITE (-6300 4775);
DISPLAY INVISIBLE (-6300 4775);
FORCEPROP 1 LAST PART_NUMBER CH4103K1B08
J 0
(-6250 4525);
DISPLAY 0.489362 (-6250 4525);
PAINT SKYBLUE (-6250 4525);
DISPLAY INVISIBLE (-6250 4525);
FORCEADD OFFPAGE..2
(-525 4125);
FORCEPROP 2 LAST $XR0 173 
J 0
(-336 4125);
DISPLAY 0.638298 (-336 4125);
PAINT MONO (-336 4125);
FORCEPROP 2 LAST CDS_LIB standard
J 0
(-525 4125);
PAINT MONO (-525 4125);
DISPLAY INVISIBLE (-525 4125);
FORCEPROP 1 LAST OFFPAGE TRUE
J 0
(-200 4000);
DISPLAY 0.872340 (-200 4000);
PAINT GREEN (-200 4000);
DISPLAY INVISIBLE (-200 4000);
FORCEPROP 1 LAST COMMENT_BODY TRUE
J 0
(-570 4030);
DISPLAY 0.872340 (-570 4030);
PAINT GREEN (-570 4030);
DISPLAY INVISIBLE (-570 4030);
FORCEPROP 2 LAST PATH I6
J 0
(-325 4175);
DISPLAY 1.021277 (-325 4175);
DISPLAY INVISIBLE (-325 4175);
FORCEADD Q_CAP..1
(-3975 2400);
FORCEPROP 1 LAST LOCATION C1506
J 0
(-4125 2525);
DISPLAY 0.489362 (-4125 2525);
PAINT SKYBLUE (-4125 2525);
FORCEPROP 2 LAST $SEC 1
J 0
(-3925 2600);
PAINT MONO (-3925 2600);
DISPLAY INVISIBLE (-3925 2600);
FORCEPROP 2 LAST CDS_SEC 1
J 0
(-3925 2600);
PAINT MONO (-3925 2600);
DISPLAY INVISIBLE (-3925 2600);
FORCEPROP 1 LASTPIN (-3975 2500) $PN 1
J 0
(-3965 2480);
DISPLAY 0.489362 (-3965 2480);
PAINT GREEN (-3965 2480);
FORCEPROP 1 LASTPIN (-3975 2300) $PN 2
J 0
(-3965 2280);
DISPLAY 0.489362 (-3965 2280);
PAINT GREEN (-3965 2280);
FORCEPROP 1 LAST MATERIAL X7R
J 0
(-4100 2325);
DISPLAY 0.489362 (-4100 2325);
PAINT SKYBLUE (-4100 2325);
FORCEPROP 1 LAST TOLERANCE 10%
J 0
(-4100 2375);
DISPLAY 0.489362 (-4100 2375);
PAINT SKYBLUE (-4100 2375);
FORCEPROP 1 LAST VOLTAGE 16V
J 0
(-4100 2425);
DISPLAY 0.489362 (-4100 2425);
PAINT SKYBLUE (-4100 2425);
FORCEPROP 1 LAST VALUE 0.1UF
J 0
(-4150 2475);
DISPLAY 0.489362 (-4150 2475);
PAINT SKYBLUE (-4150 2475);
FORCEPROP 1 LAST PACK_TYPE C0402
J 0
(-4150 2225);
DISPLAY 0.489362 (-4150 2225);
PAINT SKYBLUE (-4150 2225);
FORCEPROP 2 LAST CDS_LIB pure_quanta
J 0
(-3975 2400);
DISPLAY INVISIBLE (-3975 2400);
FORCEPROP 1 LAST PATH I62
J 0
(-3925 2550);
DISPLAY 0.978723 (-3925 2550);
PAINT WHITE (-3925 2550);
DISPLAY INVISIBLE (-3925 2550);
FORCEPROP 1 LAST PART_NUMBER CH4103K1B08
J 0
(-4325 2275);
DISPLAY 0.489362 (-4325 2275);
PAINT SKYBLUE (-4325 2275);
DISPLAY INVISIBLE (-4325 2275);
FORCEADD GND..1
(-3975 2225);
FORCEPROP 3 LASTPIN (-3975 2275) SIG_NAME GND\g
J 0
(-3965 2285);
DISPLAY 0.659574 (-3965 2285);
PAINT MONO (-3965 2285);
DISPLAY INVISIBLE (-3965 2285);
FORCEPROP 2 LAST CDS_LIB pure_quanta_power
J 0
(-3975 2225);
DISPLAY INVISIBLE (-3975 2225);
FORCEPROP 1 LAST SIZE 1B
J 0
(-3900 2175);
DISPLAY 0.872340 (-3900 2175);
PAINT GREEN (-3900 2175);
DISPLAY INVISIBLE (-3900 2175);
FORCEPROP 1 LAST HDL_POWER GND
J 0
(-3975 2375);
DISPLAY 0.872340 (-3975 2375);
PAINT GREEN (-3975 2375);
DISPLAY INVISIBLE (-3975 2375);
FORCEPROP 1 LAST PATH I63
J 0
(-3900 2225);
DISPLAY 0.872340 (-3900 2225);
PAINT AQUA (-3900 2225);
DISPLAY INVISIBLE (-3900 2225);
FORCEADD OFFPAGE..1
(-4375 2075);
FORCEPROP 2 LAST $XR0 171 
J 0
(-4627 2075);
DISPLAY 0.638298 (-4627 2075);
PAINT MONO (-4627 2075);
FORCEPROP 2 LAST CDS_LIB standard
J 0
(-4375 2075);
PAINT MONO (-4375 2075);
DISPLAY INVISIBLE (-4375 2075);
FORCEPROP 1 LAST OFFPAGE TRUE
J 0
(-4050 1950);
DISPLAY 0.872340 (-4050 1950);
PAINT GREEN (-4050 1950);
DISPLAY INVISIBLE (-4050 1950);
FORCEPROP 1 LAST COMMENT_BODY TRUE
J 0
(-4250 1975);
DISPLAY 0.872340 (-4250 1975);
PAINT GREEN (-4250 1975);
DISPLAY INVISIBLE (-4250 1975);
FORCEPROP 2 LAST PATH I64
J 0
(-4575 2125);
DISPLAY 1.021277 (-4575 2125);
DISPLAY INVISIBLE (-4575 2125);
FORCEADD OFFPAGE..1
(-4375 2025);
FORCEPROP 2 LAST $XR0 171 
J 0
(-4627 2025);
DISPLAY 0.638298 (-4627 2025);
PAINT MONO (-4627 2025);
FORCEPROP 2 LAST CDS_LIB standard
J 0
(-4375 2025);
PAINT MONO (-4375 2025);
DISPLAY INVISIBLE (-4375 2025);
FORCEPROP 1 LAST OFFPAGE TRUE
J 0
(-4050 1900);
DISPLAY 0.872340 (-4050 1900);
PAINT GREEN (-4050 1900);
DISPLAY INVISIBLE (-4050 1900);
FORCEPROP 1 LAST COMMENT_BODY TRUE
J 0
(-4250 1925);
DISPLAY 0.872340 (-4250 1925);
PAINT GREEN (-4250 1925);
DISPLAY INVISIBLE (-4250 1925);
FORCEPROP 2 LAST PATH I65
J 0
(-4575 2075);
DISPLAY 1.021277 (-4575 2075);
DISPLAY INVISIBLE (-4575 2075);
FORCEADD OFFPAGE..1
R 2
(-5100 3925);
FORCEPROP 2 LAST $XR0 173 
J 0
(-4914 3925);
DISPLAY 0.638298 (-4914 3925);
PAINT MONO (-4914 3925);
FORCEPROP 2 LAST CDS_LIB standard
J 0
(-5100 3925);
PAINT MONO (-5100 3925);
DISPLAY INVISIBLE (-5100 3925);
FORCEPROP 1 LAST OFFPAGE TRUE
J 2
(-5425 3800);
DISPLAY 0.872340 (-5425 3800);
PAINT GREEN (-5425 3800);
DISPLAY INVISIBLE (-5425 3800);
FORCEPROP 1 LAST COMMENT_BODY TRUE
J 2
(-5225 3825);
DISPLAY 0.872340 (-5225 3825);
PAINT GREEN (-5225 3825);
DISPLAY INVISIBLE (-5225 3825);
FORCEPROP 2 LAST PATH I68
J 0
(-4900 3975);
DISPLAY 1.021277 (-4900 3975);
DISPLAY INVISIBLE (-4900 3975);
FORCEADD OFFPAGE..1
(-4375 1975);
FORCEPROP 2 LAST $XR0 80 
J 0
(-4596 1975);
DISPLAY 0.638298 (-4596 1975);
PAINT MONO (-4596 1975);
FORCEPROP 2 LAST CDS_LIB standard
J 0
(-4375 1975);
PAINT MONO (-4375 1975);
DISPLAY INVISIBLE (-4375 1975);
FORCEPROP 1 LAST OFFPAGE TRUE
J 0
(-4050 1850);
DISPLAY 0.872340 (-4050 1850);
PAINT GREEN (-4050 1850);
DISPLAY INVISIBLE (-4050 1850);
FORCEPROP 1 LAST COMMENT_BODY TRUE
J 0
(-4250 1875);
DISPLAY 0.872340 (-4250 1875);
PAINT GREEN (-4250 1875);
DISPLAY INVISIBLE (-4250 1875);
FORCEPROP 2 LAST PATH I69
J 0
(-4575 2025);
DISPLAY 1.021277 (-4575 2025);
DISPLAY INVISIBLE (-4575 2025);
FORCEADD Q_RES..1
(-1675 4225);
FORCEPROP 1 LAST LOCATION R1633
J 0
(-2050 4225);
DISPLAY 0.489362 (-2050 4225);
PAINT SKYBLUE (-2050 4225);
FORCEPROP 0 LAST $SEC 1
J 0
(-1925 4275);
PAINT MONO (-1925 4275);
DISPLAY INVISIBLE (-1925 4275);
FORCEPROP 0 LAST CDS_SEC 1
J 0
(-1925 4275);
PAINT MONO (-1925 4275);
DISPLAY INVISIBLE (-1925 4275);
FORCEPROP 1 LASTPIN (-1775 4225) $PN 1
J 0
(-1763 4237);
DISPLAY 0.489362 (-1763 4237);
PAINT GREEN (-1763 4237);
FORCEPROP 1 LASTPIN (-1575 4225) $PN 2
J 0
(-1613 4237);
DISPLAY 0.489362 (-1613 4237);
PAINT GREEN (-1613 4237);
FORCEPROP 1 LAST TOLERANCE 5%
J 0
(-1575 4200);
DISPLAY 0.489362 (-1575 4200);
PAINT SKYBLUE (-1575 4200);
FORCEPROP 1 LAST VALUE 0
J 2
(-1775 4225);
DISPLAY 0.489362 (-1775 4225);
PAINT SKYBLUE (-1775 4225);
FORCEPROP 2 LAST CDS_LIB pure_quanta
J 0
(-1675 4225);
PAINT MONO (-1675 4225);
DISPLAY INVISIBLE (-1675 4225);
FORCEPROP 1 LAST WATTAGE 1/16W
J 2
(-1700 4075);
DISPLAY 0.978723 (-1700 4075);
PAINT SKYBLUE (-1700 4075);
DISPLAY INVISIBLE (-1700 4075);
FORCEPROP 1 LAST MATERIAL CHIP
J 0
(-1850 4200);
DISPLAY 0.489362 (-1850 4200);
PAINT SKYBLUE (-1850 4200);
DISPLAY INVISIBLE (-1850 4200);
FORCEPROP 1 LAST PACK_TYPE 0402LF
J 0
(-1425 4075);
DISPLAY 0.978723 (-1425 4075);
PAINT SKYBLUE (-1425 4075);
DISPLAY INVISIBLE (-1425 4075);
FORCEPROP 1 LAST PATH I7
J 0
(-1725 4375);
DISPLAY 0.978723 (-1725 4375);
PAINT WHITE (-1725 4375);
DISPLAY INVISIBLE (-1725 4375);
FORCEPROP 1 LAST PART_NUMBER CS00002JB13
J 0
(-1725 4325);
DISPLAY 0.978723 (-1725 4325);
PAINT SKYBLUE (-1725 4325);
DISPLAY INVISIBLE (-1725 4325);
FORCEADD OFFPAGE..1
(-4375 1925);
FORCEPROP 2 LAST $XR1 151 
J 0
(-4747 1925);
DISPLAY 0.638298 (-4747 1925);
PAINT MONO (-4747 1925);
FORCEPROP 2 LAST $XR0 150 
J 0
(-4627 1925);
DISPLAY 0.638298 (-4627 1925);
PAINT MONO (-4627 1925);
FORCEPROP 2 LAST CDS_LIB standard
J 0
(-4375 1925);
PAINT MONO (-4375 1925);
DISPLAY INVISIBLE (-4375 1925);
FORCEPROP 1 LAST OFFPAGE TRUE
J 0
(-4050 1800);
DISPLAY 0.872340 (-4050 1800);
PAINT GREEN (-4050 1800);
DISPLAY INVISIBLE (-4050 1800);
FORCEPROP 1 LAST COMMENT_BODY TRUE
J 0
(-4250 1825);
DISPLAY 0.872340 (-4250 1825);
PAINT GREEN (-4250 1825);
DISPLAY INVISIBLE (-4250 1825);
FORCEPROP 2 LAST PATH I70
J 0
(-4575 1975);
DISPLAY 1.021277 (-4575 1975);
DISPLAY INVISIBLE (-4575 1975);
FORCEADD UNIVERSAL_POWER..1
(-6425 3725);
FORCEPROP 3 LASTPIN (-6425 3675) SIG_NAME PVDD18_S5_P0\g
J 0
(-6415 3685);
DISPLAY 0.659574 (-6415 3685);
PAINT MONO (-6415 3685);
DISPLAY INVISIBLE (-6415 3685);
FORCEPROP 1 LAST HDL_POWER PVDD18_S5_P0
J 1
(-6400 3775);
DISPLAY 0.489362 (-6400 3775);
PAINT GREEN (-6400 3775);
FORCEPROP 2 LAST CDS_LIB pure_quanta_power
J 0
(-6425 3725);
DISPLAY INVISIBLE (-6425 3725);
FORCEPROP 1 LAST PATH I71
J 0
(-6375 3750);
DISPLAY 0.872340 (-6375 3750);
PAINT AQUA (-6375 3750);
DISPLAY INVISIBLE (-6375 3750);
FORCEADD UNIVERSAL_POWER..1
(-6450 3000);
FORCEPROP 3 LASTPIN (-6450 2950) SIG_NAME PVDD18_S5_P0\g
J 0
(-6440 2960);
DISPLAY 0.659574 (-6440 2960);
PAINT MONO (-6440 2960);
DISPLAY INVISIBLE (-6440 2960);
FORCEPROP 1 LAST HDL_POWER PVDD18_S5_P0
J 1
(-6425 3050);
DISPLAY 0.489362 (-6425 3050);
PAINT GREEN (-6425 3050);
FORCEPROP 2 LAST CDS_LIB pure_quanta_power
J 0
(-6450 3000);
PAINT MONO (-6450 3000);
DISPLAY INVISIBLE (-6450 3000);
FORCEPROP 1 LAST PATH I73
J 0
(-6400 3025);
DISPLAY 0.872340 (-6400 3025);
PAINT AQUA (-6400 3025);
DISPLAY INVISIBLE (-6400 3025);
FORCEADD Q_CAP..1
(-6325 2725);
FORCEPROP 1 LAST LOCATION C1505
J 0
(-6250 2850);
DISPLAY 0.489362 (-6250 2850);
PAINT SKYBLUE (-6250 2850);
FORCEPROP 2 LAST $SEC 1
J 0
(-6275 2925);
PAINT MONO (-6275 2925);
DISPLAY INVISIBLE (-6275 2925);
FORCEPROP 2 LAST CDS_SEC 1
J 0
(-6275 2925);
PAINT MONO (-6275 2925);
DISPLAY INVISIBLE (-6275 2925);
FORCEPROP 1 LASTPIN (-6325 2825) $PN 1
J 0
(-6315 2805);
DISPLAY 0.489362 (-6315 2805);
PAINT GREEN (-6315 2805);
FORCEPROP 1 LASTPIN (-6325 2625) $PN 2
J 0
(-6315 2605);
DISPLAY 0.489362 (-6315 2605);
PAINT GREEN (-6315 2605);
FORCEPROP 1 LAST VALUE 0.1UF
J 0
(-6250 2800);
DISPLAY 0.489362 (-6250 2800);
PAINT SKYBLUE (-6250 2800);
FORCEPROP 1 LAST PACK_TYPE C0402
J 0
(-6250 2550);
DISPLAY 0.489362 (-6250 2550);
PAINT SKYBLUE (-6250 2550);
FORCEPROP 1 LAST VOLTAGE 16V
J 0
(-6250 2750);
DISPLAY 0.489362 (-6250 2750);
PAINT SKYBLUE (-6250 2750);
FORCEPROP 1 LAST TOLERANCE 10%
J 0
(-6250 2700);
DISPLAY 0.489362 (-6250 2700);
PAINT SKYBLUE (-6250 2700);
FORCEPROP 1 LAST MATERIAL X7R
J 0
(-6250 2650);
DISPLAY 0.489362 (-6250 2650);
PAINT SKYBLUE (-6250 2650);
FORCEPROP 2 LAST CDS_LIB pure_quanta
J 0
(-6325 2725);
DISPLAY INVISIBLE (-6325 2725);
FORCEPROP 1 LAST PATH I74
J 0
(-6275 2875);
DISPLAY 0.978723 (-6275 2875);
PAINT WHITE (-6275 2875);
DISPLAY INVISIBLE (-6275 2875);
FORCEPROP 1 LAST PART_NUMBER CH4103K1B08
J 0
(-6250 2600);
DISPLAY 0.489362 (-6250 2600);
PAINT SKYBLUE (-6250 2600);
DISPLAY INVISIBLE (-6250 2600);
FORCEADD GND..1
(-6325 2500);
FORCEPROP 3 LASTPIN (-6325 2550) SIG_NAME GND\g
J 0
(-6315 2560);
DISPLAY 0.659574 (-6315 2560);
PAINT MONO (-6315 2560);
DISPLAY INVISIBLE (-6315 2560);
FORCEPROP 2 LAST CDS_LIB pure_quanta_power
J 0
(-6325 2500);
DISPLAY INVISIBLE (-6325 2500);
FORCEPROP 1 LAST SIZE 1B
J 0
(-6250 2450);
DISPLAY 0.872340 (-6250 2450);
PAINT GREEN (-6250 2450);
DISPLAY INVISIBLE (-6250 2450);
FORCEPROP 1 LAST HDL_POWER GND
J 0
(-6325 2650);
DISPLAY 0.872340 (-6325 2650);
PAINT GREEN (-6325 2650);
DISPLAY INVISIBLE (-6325 2650);
FORCEPROP 1 LAST PATH I75
J 0
(-6250 2500);
DISPLAY 0.872340 (-6250 2500);
PAINT AQUA (-6250 2500);
DISPLAY INVISIBLE (-6250 2500);
FORCEADD SN74AVC2T245RSWR..1
R 2
(-7025 4000);
FORCEPROP 1 LAST LOCATION U146
J 2
(-6775 4500);
DISPLAY 0.489362 (-6775 4500);
PAINT SKYBLUE (-6775 4500);
FORCEPROP 0 LAST $SEC 1
J 0
(-6800 4675);
PAINT MONO (-6800 4675);
DISPLAY INVISIBLE (-6800 4675);
FORCEPROP 0 LAST CDS_SEC 1
J 0
(-6800 4675);
PAINT MONO (-6800 4675);
DISPLAY INVISIBLE (-6800 4675);
FORCEPROP 0 LASTPIN (-7425 4125) $PN 8
J 2
(-7435 4135);
DISPLAY 0.489362 (-7435 4135);
PAINT MONO (-7435 4135);
FORCEPROP 0 LASTPIN (-7425 3975) $PN 9
J 2
(-7435 3985);
DISPLAY 0.489362 (-7435 3985);
PAINT MONO (-7435 3985);
FORCEPROP 0 LASTPIN (-6625 4075) $PN 5
J 0
(-6615 4085);
DISPLAY 0.489362 (-6615 4085);
PAINT MONO (-6615 4085);
FORCEPROP 0 LASTPIN (-6625 3925) $PN 4
J 0
(-6615 3935);
DISPLAY 0.489362 (-6615 3935);
PAINT MONO (-6615 3935);
FORCEPROP 0 LASTPIN (-7425 4075) $PN 10
J 2
(-7435 4085);
DISPLAY 0.489362 (-7435 4085);
PAINT MONO (-7435 4085);
FORCEPROP 0 LASTPIN (-7425 3925) $PN 1
J 2
(-7435 3935);
DISPLAY 0.489362 (-7435 3935);
PAINT MONO (-7435 3935);
FORCEPROP 0 LASTPIN (-7425 3675) $PN 3
J 2
(-7435 3685);
DISPLAY 0.489362 (-7435 3685);
PAINT MONO (-7435 3685);
FORCEPROP 0 LASTPIN (-7425 3825) $PN 2
J 2
(-7435 3835);
DISPLAY 0.489362 (-7435 3835);
PAINT MONO (-7435 3835);
FORCEPROP 0 LASTPIN (-6625 4325) $PN 7
J 0
(-6615 4335);
DISPLAY 0.489362 (-6615 4335);
PAINT MONO (-6615 4335);
FORCEPROP 0 LASTPIN (-6625 4275) $PN 6
J 0
(-6615 4285);
DISPLAY 0.489362 (-6615 4285);
PAINT MONO (-6615 4285);
FORCEPROP 2 LAST VALUE SN74AVC2T245RSWR
J 2
(-6775 4550);
DISPLAY 0.489362 (-6775 4550);
PAINT SKYBLUE (-6775 4550);
FORCEPROP 1 LAST MATERIAL IC
J 2
(-6780 4382);
DISPLAY 0.489362 (-6780 4382);
PAINT SKYBLUE (-6780 4382);
FORCEPROP 2 LAST PART_TYPE SMLF
J 2
(-6775 4600);
PAINT MONO (-6775 4600);
FORCEPROP 1 LAST NEEDS_NO_SIZE TRUE
J 2
(-7275 3682);
DISPLAY 0.723404 (-7275 3682);
PAINT GREEN (-7275 3682);
DISPLAY INVISIBLE (-7275 3682);
FORCEPROP 2 LAST CDS_LIB pure_quanta
J 2
(-7025 4000);
PAINT MONO (-7025 4000);
DISPLAY INVISIBLE (-7025 4000);
FORCEPROP 1 LAST CDS_LMAN_SYM_OUTLINE -250,375,250,-375
J 2
(-7025 4000);
DISPLAY 0.468085 (-7025 4000);
PAINT GREEN (-7025 4000);
DISPLAY INVISIBLE (-7025 4000);
FORCEPROP 1 LAST PATH I76
J 2
(-7275 3625);
DISPLAY 0.723404 (-7275 3625);
PAINT GREEN (-7275 3625);
DISPLAY INVISIBLE (-7275 3625);
FORCEPROP 1 LAST PART_NUMBER AL02T245000
J 2
(-6780 4451);
DISPLAY 0.489362 (-6780 4451);
PAINT SKYBLUE (-6780 4451);
DISPLAY INVISIBLE (-6780 4451);
FORCEADD GND..1
(-7650 3575);
FORCEPROP 3 LASTPIN (-7650 3625) SIG_NAME GND\g
J 0
(-7640 3635);
DISPLAY 0.659574 (-7640 3635);
PAINT MONO (-7640 3635);
DISPLAY INVISIBLE (-7640 3635);
FORCEPROP 2 LAST CDS_LIB pure_quanta_power
J 0
(-7650 3575);
PAINT MONO (-7650 3575);
DISPLAY INVISIBLE (-7650 3575);
FORCEPROP 1 LAST SIZE 1B
J 0
(-7575 3525);
DISPLAY 0.872340 (-7575 3525);
PAINT GREEN (-7575 3525);
DISPLAY INVISIBLE (-7575 3525);
FORCEPROP 1 LAST HDL_POWER GND
J 0
(-7650 3725);
DISPLAY 0.872340 (-7650 3725);
PAINT GREEN (-7650 3725);
DISPLAY INVISIBLE (-7650 3725);
FORCEPROP 1 LAST PATH I77
J 0
(-7575 3575);
DISPLAY 0.872340 (-7575 3575);
PAINT AQUA (-7575 3575);
DISPLAY INVISIBLE (-7575 3575);
FORCEADD UNIVERSAL_POWER..1
(-7625 3125);
FORCEPROP 3 LASTPIN (-7625 3075) SIG_NAME P3V3_AUX\g
J 0
(-7615 3085);
DISPLAY 0.659574 (-7615 3085);
PAINT MONO (-7615 3085);
DISPLAY INVISIBLE (-7615 3085);
FORCEPROP 1 LAST HDL_POWER P3V3_AUX
J 1
(-7625 3175);
DISPLAY 0.489362 (-7625 3175);
PAINT GREEN (-7625 3175);
FORCEPROP 2 LAST CDS_LIB pure_quanta_power
J 0
(-7625 3125);
PAINT MONO (-7625 3125);
DISPLAY INVISIBLE (-7625 3125);
FORCEPROP 1 LAST PATH I78
J 0
(-7575 3150);
DISPLAY 0.872340 (-7575 3150);
PAINT AQUA (-7575 3150);
DISPLAY INVISIBLE (-7575 3150);
FORCEADD Q_RES..1
(-1675 4125);
FORCEPROP 1 LAST LOCATION R1635
J 0
(-2050 4125);
DISPLAY 0.489362 (-2050 4125);
PAINT SKYBLUE (-2050 4125);
FORCEPROP 0 LAST $SEC 1
J 0
(-1925 4175);
PAINT MONO (-1925 4175);
DISPLAY INVISIBLE (-1925 4175);
FORCEPROP 0 LAST CDS_SEC 1
J 0
(-1925 4175);
PAINT MONO (-1925 4175);
DISPLAY INVISIBLE (-1925 4175);
FORCEPROP 1 LASTPIN (-1775 4125) $PN 1
J 0
(-1763 4137);
DISPLAY 0.489362 (-1763 4137);
PAINT GREEN (-1763 4137);
FORCEPROP 1 LASTPIN (-1575 4125) $PN 2
J 0
(-1613 4137);
DISPLAY 0.489362 (-1613 4137);
PAINT GREEN (-1613 4137);
FORCEPROP 1 LAST TOLERANCE 1%
J 0
(-1575 4100);
DISPLAY 0.489362 (-1575 4100);
PAINT SKYBLUE (-1575 4100);
FORCEPROP 1 LAST VALUE 22
J 2
(-1775 4125);
DISPLAY 0.489362 (-1775 4125);
PAINT SKYBLUE (-1775 4125);
FORCEPROP 2 LAST CDS_LIB pure_quanta
J 0
(-1675 4125);
PAINT MONO (-1675 4125);
DISPLAY INVISIBLE (-1675 4125);
FORCEPROP 1 LAST WATTAGE 1/16W
J 2
(-1700 3975);
DISPLAY 0.978723 (-1700 3975);
PAINT SKYBLUE (-1700 3975);
DISPLAY INVISIBLE (-1700 3975);
FORCEPROP 1 LAST MATERIAL CHIP
J 0
(-1850 4100);
DISPLAY 0.489362 (-1850 4100);
PAINT SKYBLUE (-1850 4100);
DISPLAY INVISIBLE (-1850 4100);
FORCEPROP 1 LAST PACK_TYPE 0402LF
J 0
(-1425 3975);
DISPLAY 0.978723 (-1425 3975);
PAINT SKYBLUE (-1425 3975);
DISPLAY INVISIBLE (-1425 3975);
FORCEPROP 1 LAST PATH I8
J 0
(-1725 4275);
DISPLAY 0.978723 (-1725 4275);
PAINT WHITE (-1725 4275);
DISPLAY INVISIBLE (-1725 4275);
FORCEPROP 1 LAST PART_NUMBER CS02202FB02
J 0
(-1725 4225);
DISPLAY 0.978723 (-1725 4225);
PAINT SKYBLUE (-1725 4225);
DISPLAY INVISIBLE (-1725 4225);
FORCEADD Q_CAP..1
(-7625 2800);
FORCEPROP 1 LAST LOCATION C1503
J 0
(-7775 2925);
DISPLAY 0.489362 (-7775 2925);
PAINT SKYBLUE (-7775 2925);
FORCEPROP 2 LAST $SEC 1
J 0
(-7575 3000);
PAINT MONO (-7575 3000);
DISPLAY INVISIBLE (-7575 3000);
FORCEPROP 2 LAST CDS_SEC 1
J 0
(-7575 3000);
PAINT MONO (-7575 3000);
DISPLAY INVISIBLE (-7575 3000);
FORCEPROP 1 LASTPIN (-7625 2900) $PN 1
J 0
(-7615 2880);
DISPLAY 0.489362 (-7615 2880);
PAINT GREEN (-7615 2880);
FORCEPROP 1 LASTPIN (-7625 2700) $PN 2
J 0
(-7615 2680);
DISPLAY 0.489362 (-7615 2680);
PAINT GREEN (-7615 2680);
FORCEPROP 1 LAST PACK_TYPE C0402
J 0
(-7800 2625);
DISPLAY 0.489362 (-7800 2625);
PAINT SKYBLUE (-7800 2625);
FORCEPROP 1 LAST VOLTAGE 16V
J 0
(-7750 2825);
DISPLAY 0.489362 (-7750 2825);
PAINT SKYBLUE (-7750 2825);
FORCEPROP 1 LAST TOLERANCE 10%
J 0
(-7750 2775);
DISPLAY 0.489362 (-7750 2775);
PAINT SKYBLUE (-7750 2775);
FORCEPROP 1 LAST MATERIAL X7R
J 0
(-7750 2725);
DISPLAY 0.489362 (-7750 2725);
PAINT SKYBLUE (-7750 2725);
FORCEPROP 1 LAST VALUE 0.1UF
J 0
(-7800 2875);
DISPLAY 0.489362 (-7800 2875);
PAINT SKYBLUE (-7800 2875);
FORCEPROP 2 LAST CDS_LIB pure_quanta
J 0
(-7625 2800);
DISPLAY INVISIBLE (-7625 2800);
FORCEPROP 1 LAST PATH I80
J 0
(-7575 2950);
DISPLAY 0.978723 (-7575 2950);
PAINT WHITE (-7575 2950);
DISPLAY INVISIBLE (-7575 2950);
FORCEPROP 1 LAST PART_NUMBER CH4103K1B08
J 0
(-7975 2675);
DISPLAY 0.489362 (-7975 2675);
PAINT SKYBLUE (-7975 2675);
DISPLAY INVISIBLE (-7975 2675);
FORCEADD GND..1
(-7625 2600);
FORCEPROP 3 LASTPIN (-7625 2650) SIG_NAME GND\g
J 0
(-7615 2660);
DISPLAY 0.659574 (-7615 2660);
PAINT MONO (-7615 2660);
DISPLAY INVISIBLE (-7615 2660);
FORCEPROP 2 LAST CDS_LIB pure_quanta_power
J 0
(-7625 2600);
DISPLAY INVISIBLE (-7625 2600);
FORCEPROP 1 LAST SIZE 1B
J 0
(-7550 2550);
DISPLAY 0.872340 (-7550 2550);
PAINT GREEN (-7550 2550);
DISPLAY INVISIBLE (-7550 2550);
FORCEPROP 1 LAST HDL_POWER GND
J 0
(-7625 2750);
DISPLAY 0.872340 (-7625 2750);
PAINT GREEN (-7625 2750);
DISPLAY INVISIBLE (-7625 2750);
FORCEPROP 1 LAST PATH I81
J 0
(-7550 2600);
DISPLAY 0.872340 (-7550 2600);
PAINT AQUA (-7550 2600);
DISPLAY INVISIBLE (-7550 2600);
FORCEADD UNIVERSAL_POWER..1
(-7475 1400);
FORCEPROP 3 LASTPIN (-7475 1350) SIG_NAME P3V3_AUX\g
J 0
(-7465 1360);
DISPLAY 0.659574 (-7465 1360);
PAINT MONO (-7465 1360);
DISPLAY INVISIBLE (-7465 1360);
FORCEPROP 1 LAST HDL_POWER P3V3_AUX
J 1
(-7475 1450);
DISPLAY 0.489362 (-7475 1450);
PAINT GREEN (-7475 1450);
FORCEPROP 2 LAST CDS_LIB pure_quanta_power
J 0
(-7475 1400);
DISPLAY INVISIBLE (-7475 1400);
FORCEPROP 1 LAST PATH I82
J 0
(-7425 1425);
DISPLAY 0.872340 (-7425 1425);
PAINT AQUA (-7425 1425);
DISPLAY INVISIBLE (-7425 1425);
FORCEADD Q_RES..2
(-7475 1200);
FORCEPROP 1 LAST LOCATION R1622
J 0
(-7370 1375);
DISPLAY 0.489362 (-7370 1375);
PAINT SKYBLUE (-7370 1375);
FORCEPROP 0 LAST $SEC 1
J 0
(-7350 1425);
PAINT MONO (-7350 1425);
DISPLAY INVISIBLE (-7350 1425);
FORCEPROP 0 LAST CDS_SEC 1
J 0
(-7350 1425);
PAINT MONO (-7350 1425);
DISPLAY INVISIBLE (-7350 1425);
FORCEPROP 1 LASTPIN (-7475 1300) $PN 1
J 0
(-7470 1262);
DISPLAY 0.489362 (-7470 1262);
PAINT GREEN (-7470 1262);
FORCEPROP 1 LASTPIN (-7475 1100) $PN 2
J 0
(-7470 1110);
DISPLAY 0.489362 (-7470 1110);
PAINT GREEN (-7470 1110);
FORCEPROP 1 LAST VALUE 4.7K
J 0
(-7370 1325);
DISPLAY 0.489362 (-7370 1325);
PAINT SKYBLUE (-7370 1325);
FORCEPROP 1 LAST MATERIAL CHIP
J 0
(-7375 1275);
DISPLAY 0.489362 (-7375 1275);
PAINT SKYBLUE (-7375 1275);
FORCEPROP 1 LAST TOLERANCE 5%
J 0
(-7370 1225);
DISPLAY 0.489362 (-7370 1225);
PAINT SKYBLUE (-7370 1225);
FORCEPROP 1 LAST WATTAGE 1/16W
J 0
(-7370 1175);
DISPLAY 0.489362 (-7370 1175);
PAINT SKYBLUE (-7370 1175);
FORCEPROP 1 LAST PACK_TYPE 0402LF
J 0
(-7370 1125);
DISPLAY 0.489362 (-7370 1125);
PAINT SKYBLUE (-7370 1125);
FORCEPROP 2 LAST CDS_LIB pure_quanta
J 0
(-7475 1200);
PAINT MONO (-7475 1200);
DISPLAY INVISIBLE (-7475 1200);
FORCEPROP 1 LAST PATH I83
J 0
(-7425 1375);
DISPLAY 0.978723 (-7425 1375);
PAINT WHITE (-7425 1375);
DISPLAY INVISIBLE (-7425 1375);
FORCEPROP 1 LAST PART_NUMBER CS24702JB10
J 0
(-7370 1075);
DISPLAY 0.489362 (-7370 1075);
PAINT SKYBLUE (-7370 1075);
DISPLAY INVISIBLE (-7370 1075);
FORCEADD GND..1
(-7750 1675);
FORCEPROP 3 LASTPIN (-7750 1725) SIG_NAME GND\g
J 0
(-7740 1735);
DISPLAY 0.659574 (-7740 1735);
PAINT MONO (-7740 1735);
DISPLAY INVISIBLE (-7740 1735);
FORCEPROP 1 LAST SIZE 1B
J 0
(-7675 1625);
DISPLAY 0.872340 (-7675 1625);
PAINT GREEN (-7675 1625);
DISPLAY INVISIBLE (-7675 1625);
FORCEPROP 2 LAST CDS_LIB pure_quanta_power
J 0
(-7750 1675);
PAINT MONO (-7750 1675);
DISPLAY INVISIBLE (-7750 1675);
FORCEPROP 1 LAST HDL_POWER GND
J 0
(-7750 1825);
DISPLAY 0.872340 (-7750 1825);
PAINT GREEN (-7750 1825);
DISPLAY INVISIBLE (-7750 1825);
FORCEPROP 1 LAST PATH I84
J 0
(-7675 1675);
DISPLAY 0.872340 (-7675 1675);
PAINT AQUA (-7675 1675);
DISPLAY INVISIBLE (-7675 1675);
FORCEADD GND..1
(-7475 300);
FORCEPROP 3 LASTPIN (-7475 350) SIG_NAME GND\g
J 0
(-7465 360);
DISPLAY 0.659574 (-7465 360);
PAINT MONO (-7465 360);
DISPLAY INVISIBLE (-7465 360);
FORCEPROP 1 LAST SIZE 1B
J 0
(-7400 250);
DISPLAY 0.872340 (-7400 250);
PAINT GREEN (-7400 250);
DISPLAY INVISIBLE (-7400 250);
FORCEPROP 2 LAST CDS_LIB pure_quanta_power
J 0
(-7475 300);
PAINT MONO (-7475 300);
DISPLAY INVISIBLE (-7475 300);
FORCEPROP 1 LAST HDL_POWER GND
J 0
(-7475 450);
DISPLAY 0.872340 (-7475 450);
PAINT GREEN (-7475 450);
DISPLAY INVISIBLE (-7475 450);
FORCEPROP 1 LAST PATH I85
J 0
(-7400 300);
DISPLAY 0.872340 (-7400 300);
PAINT AQUA (-7400 300);
DISPLAY INVISIBLE (-7400 300);
FORCEADD Q_RES..1
(-1675 4075);
FORCEPROP 1 LAST LOCATION R1636
J 0
(-2050 4075);
DISPLAY 0.489362 (-2050 4075);
PAINT SKYBLUE (-2050 4075);
FORCEPROP 0 LAST $SEC 1
J 0
(-1925 4125);
PAINT MONO (-1925 4125);
DISPLAY INVISIBLE (-1925 4125);
FORCEPROP 0 LAST CDS_SEC 1
J 0
(-1925 4125);
PAINT MONO (-1925 4125);
DISPLAY INVISIBLE (-1925 4125);
FORCEPROP 1 LASTPIN (-1775 4075) $PN 1
J 0
(-1763 4087);
DISPLAY 0.489362 (-1763 4087);
PAINT GREEN (-1763 4087);
FORCEPROP 1 LASTPIN (-1575 4075) $PN 2
J 0
(-1613 4087);
DISPLAY 0.489362 (-1613 4087);
PAINT GREEN (-1613 4087);
FORCEPROP 1 LAST TOLERANCE 1%
J 0
(-1575 4050);
DISPLAY 0.489362 (-1575 4050);
PAINT SKYBLUE (-1575 4050);
FORCEPROP 1 LAST VALUE 22
J 2
(-1775 4075);
DISPLAY 0.489362 (-1775 4075);
PAINT SKYBLUE (-1775 4075);
FORCEPROP 2 LAST CDS_LIB pure_quanta
J 0
(-1675 4075);
PAINT MONO (-1675 4075);
DISPLAY INVISIBLE (-1675 4075);
FORCEPROP 1 LAST WATTAGE 1/16W
J 2
(-1700 3925);
DISPLAY 0.978723 (-1700 3925);
PAINT SKYBLUE (-1700 3925);
DISPLAY INVISIBLE (-1700 3925);
FORCEPROP 1 LAST MATERIAL CHIP
J 0
(-1850 4050);
DISPLAY 0.489362 (-1850 4050);
PAINT SKYBLUE (-1850 4050);
DISPLAY INVISIBLE (-1850 4050);
FORCEPROP 1 LAST PACK_TYPE 0402LF
J 0
(-1425 3925);
DISPLAY 0.978723 (-1425 3925);
PAINT SKYBLUE (-1425 3925);
DISPLAY INVISIBLE (-1425 3925);
FORCEPROP 1 LAST PATH I9
J 0
(-1725 4225);
DISPLAY 0.978723 (-1725 4225);
PAINT WHITE (-1725 4225);
DISPLAY INVISIBLE (-1725 4225);
FORCEPROP 1 LAST PART_NUMBER CS02202FB02
J 0
(-1725 4175);
DISPLAY 0.978723 (-1725 4175);
PAINT SKYBLUE (-1725 4175);
DISPLAY INVISIBLE (-1725 4175);
FORCEADD OFFPAGE..1
(-8300 4125);
FORCEPROP 2 LAST $XR0 172 
J 0
(-8552 4125);
DISPLAY 0.638298 (-8552 4125);
PAINT MONO (-8552 4125);
FORCEPROP 2 LAST CDS_LIB standard
J 0
(-8300 4125);
PAINT MONO (-8300 4125);
DISPLAY INVISIBLE (-8300 4125);
FORCEPROP 1 LAST OFFPAGE TRUE
J 0
(-7975 4000);
DISPLAY 0.872340 (-7975 4000);
PAINT GREEN (-7975 4000);
DISPLAY INVISIBLE (-7975 4000);
FORCEPROP 1 LAST COMMENT_BODY TRUE
J 0
(-8175 4025);
DISPLAY 0.872340 (-8175 4025);
PAINT GREEN (-8175 4025);
DISPLAY INVISIBLE (-8175 4025);
FORCEPROP 2 LAST PATH I90
J 0
(-8500 4175);
DISPLAY 1.021277 (-8500 4175);
DISPLAY INVISIBLE (-8500 4175);
FORCEADD OFFPAGE..5
(-8975 3975);
FORCEPROP 2 LAST $XR0 172 
J 0
(-9260 3975);
DISPLAY 0.638298 (-9260 3975);
PAINT MONO (-9260 3975);
FORCEPROP 2 LAST CDS_LIB standard
J 0
(-8975 3975);
DISPLAY INVISIBLE (-8975 3975);
FORCEPROP 1 LAST OFFPAGE TRUE
J 0
(-8650 3850);
DISPLAY 0.872340 (-8650 3850);
PAINT GREEN (-8650 3850);
DISPLAY INVISIBLE (-8650 3850);
FORCEPROP 1 LAST COMMENT_BODY TRUE
J 0
(-8875 3900);
DISPLAY 0.872340 (-8875 3900);
PAINT GREEN (-8875 3900);
DISPLAY INVISIBLE (-8875 3900);
FORCEPROP 2 LAST PATH I91
J 0
(-9225 4025);
DISPLAY 1.021277 (-9225 4025);
DISPLAY INVISIBLE (-9225 4025);
FORCEADD Q_RES..1
(-8325 3350);
FORCEPROP 1 LAST LOCATION R1619
J 0
(-8375 3400);
DISPLAY 0.489362 (-8375 3400);
PAINT SKYBLUE (-8375 3400);
FORCEPROP 0 LAST $SEC 1
J 0
(-8375 3450);
PAINT MONO (-8375 3450);
DISPLAY INVISIBLE (-8375 3450);
FORCEPROP 0 LAST CDS_SEC 1
J 0
(-8375 3450);
PAINT MONO (-8375 3450);
DISPLAY INVISIBLE (-8375 3450);
FORCEPROP 1 LASTPIN (-8425 3350) $PN 1
J 0
(-8413 3362);
DISPLAY 0.489362 (-8413 3362);
PAINT GREEN (-8413 3362);
FORCEPROP 1 LASTPIN (-8225 3350) $PN 2
J 0
(-8263 3362);
DISPLAY 0.489362 (-8263 3362);
PAINT GREEN (-8263 3362);
FORCEPROP 1 LAST VALUE 0
J 2
(-8175 3350);
DISPLAY 0.489362 (-8175 3350);
PAINT SKYBLUE (-8175 3350);
FORCEPROP 1 LAST MATERIAL CHIP
J 0
(-8250 3325);
DISPLAY 0.489362 (-8250 3325);
PAINT SKYBLUE (-8250 3325);
FORCEPROP 1 LAST PACK_TYPE 0402LF
J 0
(-8075 3200);
DISPLAY 0.978723 (-8075 3200);
PAINT SKYBLUE (-8075 3200);
DISPLAY INVISIBLE (-8075 3200);
FORCEPROP 1 LAST TOLERANCE 5%
J 0
(-8325 3250);
DISPLAY 0.978723 (-8325 3250);
PAINT SKYBLUE (-8325 3250);
DISPLAY INVISIBLE (-8325 3250);
FORCEPROP 1 LAST WATTAGE 1/16W
J 2
(-8350 3200);
DISPLAY 0.978723 (-8350 3200);
PAINT SKYBLUE (-8350 3200);
DISPLAY INVISIBLE (-8350 3200);
FORCEPROP 2 LAST CDS_LIB pure_quanta
J 0
(-8325 3350);
PAINT MONO (-8325 3350);
DISPLAY INVISIBLE (-8325 3350);
FORCEPROP 1 LAST PATH I92
J 0
(-8375 3500);
DISPLAY 0.978723 (-8375 3500);
PAINT WHITE (-8375 3500);
DISPLAY INVISIBLE (-8375 3500);
FORCEPROP 1 LAST PART_NUMBER CS00002JB13
J 0
(-8375 3450);
DISPLAY 0.978723 (-8375 3450);
PAINT SKYBLUE (-8375 3450);
DISPLAY INVISIBLE (-8375 3450);
FORCEADD OFFPAGE..1
(-8725 2225);
FORCEPROP 2 LAST $XR0 171 
J 0
(-9007 2225);
DISPLAY 0.638298 (-9007 2225);
PAINT MONO (-9007 2225);
FORCEPROP 2 LAST CDS_LIB standard
J 0
(-8725 2225);
PAINT MONO (-8725 2225);
DISPLAY INVISIBLE (-8725 2225);
FORCEPROP 1 LAST OFFPAGE TRUE
J 0
(-8400 2100);
DISPLAY 0.872340 (-8400 2100);
PAINT GREEN (-8400 2100);
DISPLAY INVISIBLE (-8400 2100);
FORCEPROP 1 LAST COMMENT_BODY TRUE
J 0
(-8600 2125);
DISPLAY 0.872340 (-8600 2125);
PAINT GREEN (-8600 2125);
DISPLAY INVISIBLE (-8600 2125);
FORCEPROP 2 LAST PATH I93
J 0
(-8975 2275);
DISPLAY 1.021277 (-8975 2275);
DISPLAY INVISIBLE (-8975 2275);
FORCEADD OFFPAGE..5
(-8725 2075);
FORCEPROP 2 LAST $XR0 171 
J 0
(-8980 2075);
DISPLAY 0.638298 (-8980 2075);
PAINT MONO (-8980 2075);
FORCEPROP 2 LAST CDS_LIB standard
J 0
(-8725 2075);
DISPLAY INVISIBLE (-8725 2075);
FORCEPROP 1 LAST OFFPAGE TRUE
J 0
(-8400 1950);
DISPLAY 0.872340 (-8400 1950);
PAINT GREEN (-8400 1950);
DISPLAY INVISIBLE (-8400 1950);
FORCEPROP 1 LAST COMMENT_BODY TRUE
J 0
(-8625 2000);
DISPLAY 0.872340 (-8625 2000);
PAINT GREEN (-8625 2000);
DISPLAY INVISIBLE (-8625 2000);
FORCEPROP 2 LAST PATH I94
J 0
(-8975 2125);
DISPLAY 1.021277 (-8975 2125);
DISPLAY INVISIBLE (-8975 2125);
FORCEADD OFFPAGE..1
(-8650 600);
FORCEPROP 2 LAST $XR0 167 
J 0
(-8902 600);
DISPLAY 0.638298 (-8902 600);
PAINT MONO (-8902 600);
FORCEPROP 2 LAST CDS_LIB standard
J 0
(-8650 600);
PAINT MONO (-8650 600);
DISPLAY INVISIBLE (-8650 600);
FORCEPROP 1 LAST OFFPAGE TRUE
J 0
(-8325 475);
DISPLAY 0.872340 (-8325 475);
PAINT GREEN (-8325 475);
DISPLAY INVISIBLE (-8325 475);
FORCEPROP 1 LAST COMMENT_BODY TRUE
J 0
(-8525 500);
DISPLAY 0.872340 (-8525 500);
PAINT GREEN (-8525 500);
DISPLAY INVISIBLE (-8525 500);
FORCEPROP 2 LAST PATH I95
J 0
(-8850 650);
DISPLAY 1.021277 (-8850 650);
DISPLAY INVISIBLE (-8850 650);
FORCEADD Q_RES..1
(-1675 4175);
FORCEPROP 1 LAST LOCATION R1634
J 0
(-2050 4175);
DISPLAY 0.489362 (-2050 4175);
PAINT SKYBLUE (-2050 4175);
FORCEPROP 0 LAST $SEC 1
J 0
(-2000 4225);
DISPLAY 0.680851 (-2000 4225);
PAINT MONO (-2000 4225);
DISPLAY INVISIBLE (-2000 4225);
FORCEPROP 0 LAST CDS_SEC 1
J 0
(-2000 4225);
DISPLAY 1.021277 (-2000 4225);
DISPLAY INVISIBLE (-2000 4225);
FORCEPROP 1 LASTPIN (-1775 4175) $PN 1
J 0
(-1763 4187);
DISPLAY 0.489362 (-1763 4187);
PAINT MONO (-1763 4187);
FORCEPROP 1 LASTPIN (-1575 4175) $PN 2
J 0
(-1613 4187);
DISPLAY 0.489362 (-1613 4187);
PAINT MONO (-1613 4187);
FORCEPROP 1 LAST TOLERANCE 5%
J 0
(-1575 4150);
DISPLAY 0.489362 (-1575 4150);
PAINT SKYBLUE (-1575 4150);
FORCEPROP 1 LAST VALUE 0
J 2
(-1775 4175);
DISPLAY 0.489362 (-1775 4175);
PAINT SKYBLUE (-1775 4175);
FORCEPROP 2 LAST CDS_LIB pure_quanta
J 0
(-1675 4175);
DISPLAY INVISIBLE (-1675 4175);
FORCEPROP 1 LAST WATTAGE 1/16W
J 2
(-1700 4025);
DISPLAY 0.978723 (-1700 4025);
PAINT SKYBLUE (-1700 4025);
DISPLAY INVISIBLE (-1700 4025);
FORCEPROP 1 LAST MATERIAL CHIP
J 0
(-1850 4150);
DISPLAY 0.489362 (-1850 4150);
PAINT SKYBLUE (-1850 4150);
DISPLAY INVISIBLE (-1850 4150);
FORCEPROP 1 LAST PACK_TYPE 0402LF
J 0
(-1425 4025);
DISPLAY 0.978723 (-1425 4025);
PAINT SKYBLUE (-1425 4025);
DISPLAY INVISIBLE (-1425 4025);
FORCEPROP 1 LAST PATH I96
J 0
(-1725 4325);
DISPLAY 0.978723 (-1725 4325);
PAINT WHITE (-1725 4325);
DISPLAY INVISIBLE (-1725 4325);
FORCEPROP 1 LAST PART_NUMBER CS00002JB13
J 0
(-1725 4275);
DISPLAY 0.978723 (-1725 4275);
PAINT SKYBLUE (-1725 4275);
DISPLAY INVISIBLE (-1725 4275);
FORCEADD CAD_NOTE..1
(-5600 3750);
FORCEPROP 0 LAST L1 R6111 PLACE CLOSE TO U146
J 0
(-5750 3625);
DISPLAY 0.617021 (-5750 3625);
PAINT WHITE (-5750 3625);
FORCEPROP 2 LAST CDS_LIB pure_quanta_power
J 0
(-5600 3750);
DISPLAY INVISIBLE (-5600 3750);
FORCEPROP 1 LAST COMMENT_BODY TRUE
J 0
(-5575 3850);
DISPLAY 0.574468 (-5575 3850);
PAINT WHITE (-5575 3850);
DISPLAY INVISIBLE (-5575 3850);
FORCEADD CAD_NOTE..1
(-8625 3825);
FORCEPROP 0 LAST L1 R6108 PLACE CLOSE TO U146
J 0
(-8775 3700);
DISPLAY 0.617021 (-8775 3700);
PAINT WHITE (-8775 3700);
FORCEPROP 2 LAST CDS_LIB pure_quanta_power
J 0
(-8625 3825);
DISPLAY INVISIBLE (-8625 3825);
FORCEPROP 1 LAST COMMENT_BODY TRUE
J 0
(-8600 3925);
DISPLAY 0.574468 (-8600 3925);
PAINT WHITE (-8600 3925);
DISPLAY INVISIBLE (-8600 3925);
FORCEADD CAD_NOTE..1
(-6250 875);
FORCEPROP 0 LAST S1 PLACE U146 AND U147 CLOSER
J 0
(-6375 750);
DISPLAY 0.808511 (-6375 750);
PAINT WHITE (-6375 750);
FORCEPROP 2 LAST CDS_LIB pure_quanta_power
J 0
(-6250 875);
DISPLAY INVISIBLE (-6250 875);
FORCEPROP 1 LAST COMMENT_BODY TRUE
J 0
(-6225 975);
DISPLAY 0.978723 (-6225 975);
DISPLAY INVISIBLE (-6225 975);
FORCEADD CAD_NOTE..1
(-3250 850);
FORCEPROP 0 LAST S1 PLACE U149 AND U148 CLOSER
J 0
(-3375 725);
DISPLAY 0.808511 (-3375 725);
PAINT WHITE (-3375 725);
FORCEPROP 2 LAST CDS_LIB pure_quanta_power
J 0
(-3250 850);
DISPLAY INVISIBLE (-3250 850);
FORCEPROP 1 LAST COMMENT_BODY TRUE
J 0
(-3225 950);
DISPLAY 0.978723 (-3225 950);
DISPLAY INVISIBLE (-3225 950);
FORCEADD QUANTA_TITLE_BLOCK_C..1
(0 0);
FORCEPROP 0 LAST CDS_CON_LAST_MODIFIED Thu Sep 14 16:12:16 2023
J 0
(-1885 15);
DISPLAY INVISIBLE (-1885 15);
FORCEPROP 1 LAST CUSTOM_TXT_CDS <CON_LAST_MODIFIED>
J 0
(-1885 15);
DISPLAY 0.978723 (-1885 15);
FORCEPROP 2 LAST CUSTOM_TXT_CDS <XR_PAGE_TITLE>
J 0
(-7890 5250);
DISPLAY 0.638298 (-7890 5250);
PAINT PINK (-7890 5250);
DISPLAY INVISIBLE (-7890 5250);
FORCEPROP 1 LAST CUSTOM_TXT_CDS <NAME_2>
J 0
(-3175 50);
FORCEPROP 1 LAST CUSTOM_TXT_CDS <NAME_1>
J 0
(-3175 175);
FORCEPROP 1 LAST CUSTOM_TXT_CDS <Q_NUMBER>
J 0
(-1403 103);
DISPLAY 1.212766 (-1403 103);
FORCEPROP 1 LAST CUSTOM_TXT_CDS <Q_PROJ>
J 0
(-2382 102);
DISPLAY 1.212766 (-2382 102);
FORCEPROP 1 LAST CUSTOM_TXT_CDS <Q_REV>
J 0
(-184 103);
DISPLAY 1.212766 (-184 103);
FORCEPROP 1 LAST CUSTOM_TXT_CDS <CON_PAGE_NUM> OF <CON_TOTAL_PAGES>
J 0
(-446 18);
DISPLAY 0.978723 (-446 18);
FORCEPROP 1 LAST Q_TITLE JTAG - HDT & BMC MUX
J 0
(-9250 75);
DISPLAY 2.446809 (-9250 75);
PAINT GREEN (-9250 75);
FORCEPROP 2 LAST PAGE_BORDER TRUE
J 0
(-7890 5250);
DISPLAY 0.638298 (-7890 5250);
PAINT PINK (-7890 5250);
DISPLAY INVISIBLE (-7890 5250);
FORCEPROP 1 LAST CDS_LMAN_SYM_OUTLINE -9475,6775,100,-125
J 0
(0 0);
DISPLAY 0.468085 (0 0);
PAINT GREEN (0 0);
DISPLAY INVISIBLE (0 0);
FORCEPROP 2 LAST CDS_LIB pure_quanta
J 0
(0 0);
DISPLAY INVISIBLE (0 0);
FORCEPROP 2 LAST CDS_XR_PAGE_TITLE CR-172 : @T6G_MB_LIB.T6G(SCH_1):PAGE172
J 0
(-7890 5250);
DISPLAY 0.638298 (-7890 5250);
PAINT PINK (-7890 5250);
DISPLAY INVISIBLE (-7890 5250);
FORCEPROP 1 LAST Q_DEPT BU9
J 1
(-3763 49);
DISPLAY 1.957447 (-3763 49);
PAINT GREEN (-3763 49);
DISPLAY INVISIBLE (-3763 49);
FORCEPROP 1 LAST COMMENT_BODY TRUE
J 0
(12 -13);
DISPLAY 0.978723 (12 -13);
PAINT GREEN (12 -13);
DISPLAY INVISIBLE (12 -13);
FORCEADD CAD_NOTE..1
(-5075 5250);
FORCEPROP 0 LAST S1 PLACE CAP AND RES NEAR J54
J 0
(-5200 5125);
DISPLAY 0.808511 (-5200 5125);
PAINT WHITE (-5200 5125);
FORCEPROP 2 LAST CDS_LIB pure_quanta_power
J 0
(-5075 5250);
DISPLAY INVISIBLE (-5075 5250);
FORCEPROP 1 LAST COMMENT_BODY TRUE
J 0
(-5050 5350);
DISPLAY 0.978723 (-5050 5350);
DISPLAY INVISIBLE (-5050 5350);
FORCEADD DNS..2
(-5125 4400);
PAINT RED (-5125 4400);
FORCEPROP 2 LAST CDS_LIB mstr_misc
J 0
(-5125 4400);
PAINT MONO (-5125 4400);
DISPLAY INVISIBLE (-5125 4400);
FORCEPROP 1 LAST COMMENT_BODY TRUE
J 0
(-5125 4400);
PAINT RED (-5125 4400);
DISPLAY INVISIBLE (-5125 4400);
WIRE 16 -1 (-2650 4450)(-2650 4425);
WIRE 16 -1 (-3675 5150)(-3675 5225);
WIRE 16 -1 (-2350 5225)(-2350 5150);
WIRE 16 -1 (-2125 5225)(-2125 5150);
WIRE 16 -1 (-2575 5225)(-2575 5150);
WIRE 16 -1 (-2800 5225)(-2800 5150);
WIRE 16 -1 (-6050 6400)(-6050 6350);
WIRE 16 -1 (-7000 5275)(-7000 5200);
WIRE 16 -1 (-5125 4325)(-5125 4250);
WIRE 16 -1 (-8075 3050)(-8075 2975);
WIRE 16 -1 (-800 3675)(-800 3500);
WIRE 16 -1 (-1125 3675)(-1125 3500);
WIRE 16 -1 (-1500 3675)(-1500 3500);
WIRE 16 -1 (-2650 2550)(-2650 2525);
WIRE 16 -1 (-3975 4450)(-3975 4425);
WIRE 16 -1 (-6350 4525)(-6350 4450);
WIRE 16 -1 (-3975 2300)(-3975 2275);
WIRE 16 -1 (-6425 3650)(-6425 3675);
WIRE 16 -1 (-6325 2625)(-6325 2550);
WIRE 16 -1 (-7625 2700)(-7625 2650);
WIRE 16 -1 (-7475 1350)(-7475 1300);
WIRE 16 -1 (-7475 350)(-7475 500);
WIRE 16 -1 (-5125 4575)(-5125 4525);
WIRE 16 -1 (-5425 4575)(-5125 4575);
WIRE 16 -1 (-5425 4075)(-5425 4575);
WIRE 16 -1 (-5150 4075)(-5425 4075);
FORCEPROP 2 LAST SIG_NAME JTAG_TDI
J 2
(-5235 4085);
DISPLAY 0.489362 (-5235 4085);
WIRE 16 -1 (-5425 4075)(-5575 4075);
WIRE 16 -1 (-2925 5550)(-2125 5550);
FORCEPROP 2 LAST SIG_NAME CPU0_HDT_CONN_TESTEN
J 0
(-2135 5560);
DISPLAY 0.489362 (-2135 5560);
WIRE 16 -1 (-1675 5550)(-2125 5550);
WIRE 16 -1 (-2125 5550)(-2125 5425);
WIRE 16 -1 (-3400 6300)(-3525 6300);
WIRE 16 -1 (-3275 6300)(-3400 6300);
WIRE 16 -1 (-3400 6225)(-3400 6300);
WIRE 16 -1 (-3525 6225)(-3525 6300);
WIRE 16 -1 (-3525 6300)(-3650 6300);
WIRE 16 -1 (-3650 6350)(-3650 6300);
WIRE 16 -1 (-3650 6300)(-3650 6225);
WIRE 16 -1 (-3275 6300)(-3150 6300);
WIRE 16 -1 (-3275 6225)(-3275 6300);
WIRE 16 -1 (-3150 6300)(-3150 6225);
WIRE 16 -1 (-2825 4425)(-2725 4425);
WIRE 16 -1 (-2725 4725)(-2725 4425);
WIRE 16 -1 (-2650 4725)(-2725 4725);
WIRE 16 -1 (-2725 4800)(-2725 4725);
WIRE 16 -1 (-2650 4650)(-2650 4725);
WIRE 16 -1 (-5375 5800)(-5475 5800);
WIRE 16 -1 (-5475 5850)(-5475 5800);
WIRE 16 -1 (-5475 5800)(-5475 5550);
WIRE 16 -1 (-5375 5550)(-5475 5550);
WIRE 16 -1 (-5475 5550)(-5475 5400);
WIRE 16 -1 (-5375 5850)(-5475 5850);
WIRE 16 -1 (-5600 6150)(-5600 5950);
WIRE 16 -1 (-5375 5950)(-5600 5950);
WIRE 16 -1 (-5600 5950)(-5600 5500);
WIRE 16 -1 (-5600 5500)(-5375 5500);
WIRE 16 -1 (-3625 3775)(-3750 3775);
WIRE 16 -1 (-3750 3825)(-3750 3775);
WIRE 16 -1 (-3750 3875)(-3750 3825);
WIRE 16 -1 (-3625 3825)(-3750 3825);
WIRE 16 -1 (-3625 3875)(-3750 3875);
WIRE 16 -1 (-3750 3925)(-3750 3875);
WIRE 16 -1 (-3750 4425)(-3750 3925);
WIRE 16 -1 (-3625 3925)(-3750 3925);
WIRE 16 -1 (-3750 4700)(-3750 4425);
WIRE 16 -1 (-3625 4425)(-3750 4425);
WIRE 16 -1 (-3750 4775)(-3750 4700);
WIRE 16 -1 (-3750 4700)(-3975 4700);
WIRE 16 -1 (-3975 4650)(-3975 4700);
WIRE 16 -1 (-2825 3675)(-2700 3675);
WIRE 16 -1 (-2700 3550)(-2700 3675);
WIRE 16 -1 (-2650 2750)(-2650 2825);
WIRE 16 -1 (-2650 2825)(-2725 2825);
WIRE 16 -1 (-2725 2900)(-2725 2825);
WIRE 16 -1 (-2725 2275)(-2725 2825);
WIRE 16 -1 (-2850 2275)(-2725 2275);
WIRE 16 -1 (-3650 1625)(-3750 1625);
WIRE 16 -1 (-3750 1675)(-3750 1625);
WIRE 16 -1 (-3650 1675)(-3750 1675);
WIRE 16 -1 (-3750 1725)(-3750 1675);
WIRE 16 -1 (-3650 1725)(-3750 1725);
WIRE 16 -1 (-3750 1775)(-3750 1725);
WIRE 16 -1 (-3750 2275)(-3750 1775);
WIRE 16 -1 (-3650 1775)(-3750 1775);
WIRE 16 -1 (-3750 2550)(-3750 2275);
WIRE 16 -1 (-3650 2275)(-3750 2275);
WIRE 16 -1 (-3750 2625)(-3750 2550);
WIRE 16 -1 (-3750 2550)(-3975 2550);
WIRE 16 -1 (-3975 2500)(-3975 2550);
WIRE 16 -1 (-2850 1525)(-2725 1525);
WIRE 16 -1 (-2725 1400)(-2725 1525);
WIRE 16 -1 (-7425 4075)(-7725 4075);
WIRE 16 -1 (-7725 4075)(-7725 4700);
WIRE 16 -1 (-7725 4700)(-6475 4700);
WIRE 16 -1 (-6475 4700)(-6475 4800);
WIRE 16 -1 (-6475 4325)(-6475 4700);
WIRE 16 -1 (-6625 4325)(-6475 4325);
WIRE 16 -1 (-6475 4275)(-6475 4325);
WIRE 16 -1 (-6350 4800)(-6475 4800);
WIRE 16 -1 (-6475 4850)(-6475 4800);
WIRE 16 -1 (-6350 4725)(-6350 4800);
WIRE 16 -1 (-6625 4275)(-6475 4275);
WIRE 16 -1 (-6325 2825)(-6325 2900);
WIRE 16 -1 (-6325 2900)(-6450 2900);
WIRE 16 -1 (-6450 2950)(-6450 2900);
WIRE 16 -1 (-6450 2375)(-6450 2900);
WIRE 16 -1 (-6600 2375)(-6450 2375);
WIRE 16 -1 (-7425 3925)(-7650 3925);
WIRE 16 -1 (-7650 3925)(-7650 3675);
WIRE 16 -1 (-7650 3675)(-7425 3675);
WIRE 16 -1 (-7650 3675)(-7650 3625);
WIRE 16 -1 (-6600 2425)(-6550 2425);
WIRE 16 -1 (-6550 2425)(-6550 2800);
WIRE 16 -1 (-6550 2800)(-7450 2800);
WIRE 16 -1 (-7450 2975)(-7450 2800);
WIRE 16 -1 (-7450 2175)(-7450 2800);
WIRE 16 -1 (-7400 2175)(-7450 2175);
WIRE 16 -1 (-7450 2975)(-7625 2975);
WIRE 16 -1 (-7625 3075)(-7625 2975);
WIRE 16 -1 (-7625 2900)(-7625 2975);
WIRE 16 -1 (-7400 2025)(-7750 2025);
WIRE 16 -1 (-7750 2025)(-7750 1775);
WIRE 16 -1 (-7750 1775)(-7400 1775);
WIRE 16 -1 (-7750 1775)(-7750 1725);
WIRE 16 -1 (-3875 5850)(-3400 5850);
WIRE 16 -1 (-3400 5850)(-2575 5850);
WIRE 16 -1 (-3400 6025)(-3400 5850);
WIRE 16 -1 (-1700 5850)(-2575 5850);
FORCEPROP 2 LAST SIG_NAME HDT_HDR_TDI
J 0
(-2135 5860);
DISPLAY 0.489362 (-2135 5860);
WIRE 16 -1 (-2575 5850)(-2575 5425);
WIRE 16 -1 (-4875 5750)(-1700 5750);
FORCEPROP 2 LAST SIG_NAME HDT_HDR_PWROK
J 0
(-2135 5760);
DISPLAY 0.489362 (-2135 5760);
WIRE 16 -1 (-4875 5700)(-1700 5700);
FORCEPROP 2 LAST SIG_NAME HDT_HDR_RESET_N
J 0
(-2135 5710);
DISPLAY 0.489362 (-2135 5710);
WIRE 16 -1 (-2925 5600)(-2350 5600);
WIRE 16 -1 (-1675 5600)(-2350 5600);
FORCEPROP 2 LAST SIG_NAME HDT_HDR_DBREQ_N
J 0
(-2135 5610);
DISPLAY 0.489362 (-2135 5610);
WIRE 16 -1 (-2350 5600)(-2350 5425);
WIRE 16 -1 (-3275 6025)(-3275 5800);
WIRE 16 -1 (-3275 5800)(-1700 5800);
FORCEPROP 2 LAST SIG_NAME HDT_HDR_TDO
J 0
(-2135 5810);
DISPLAY 0.489362 (-2135 5810);
WIRE 16 -1 (-4875 5800)(-3275 5800);
WIRE 16 -1 (-3875 5900)(-3525 5900);
WIRE 16 -1 (-1700 5900)(-3525 5900);
FORCEPROP 2 LAST SIG_NAME HDT_HDR_TMS
J 0
(-2135 5910);
DISPLAY 0.489362 (-2135 5910);
WIRE 16 -1 (-3525 6025)(-3525 5900);
WIRE 16 -1 (-2850 2075)(-2275 2075);
WIRE 16 -1 (-2275 2075)(-2275 4225);
WIRE 16 -1 (-1775 4225)(-2275 4225);
WIRE 16 -1 (-2825 4225)(-2275 4225);
FORCEPROP 2 LAST SIG_NAME JTAG_TCK_R
J 0
(-2725 4235);
DISPLAY 0.489362 (-2725 4235);
FORCEPROP 2 LASTPROP $XRERR UNIQUE?
J 0
(-2965 4235);
DISPLAY 0.638298 (-2965 4235);
PAINT MONO (-2965 4235);
DISPLAY INVISIBLE (-2965 4235);
WIRE 16 -1 (-1575 4225)(-1500 4225);
WIRE 16 -1 (-1500 4225)(-575 4225);
FORCEPROP 2 LAST SIG_NAME JTAG_TCK
J 0
(-1435 4235);
DISPLAY 0.489362 (-1435 4235);
WIRE 16 -1 (-1500 3875)(-1500 4225);
WIRE 16 -1 (-1775 4175)(-2225 4175);
WIRE 16 -1 (-2225 4175)(-2825 4175);
FORCEPROP 2 LAST SIG_NAME JTAG_TMS_R
J 0
(-2725 4185);
DISPLAY 0.489362 (-2725 4185);
FORCEPROP 2 LASTPROP $XRERR UNIQUE?
J 0
(-2965 4185);
DISPLAY 0.638298 (-2965 4185);
PAINT MONO (-2965 4185);
DISPLAY INVISIBLE (-2965 4185);
WIRE 16 -1 (-2225 2025)(-2225 4175);
WIRE 16 -1 (-2850 2025)(-2225 2025);
WIRE 16 -1 (-575 4175)(-1575 4175);
FORCEPROP 2 LAST SIG_NAME JTAG_TMS
J 0
(-1435 4185);
DISPLAY 0.489362 (-1435 4185);
WIRE 16 -1 (-3625 4225)(-4325 4225);
FORCEPROP 2 LAST SIG_NAME HDT_HDR_TCK
J 0
(-4250 4235);
DISPLAY 0.489362 (-4250 4235);
WIRE 16 -1 (-3625 4125)(-4325 4125);
FORCEPROP 2 LAST SIG_NAME HDT_HDR_TRST_N
J 0
(-4250 4135);
DISPLAY 0.489362 (-4250 4135);
WIRE 16 -1 (-3625 4175)(-4325 4175);
FORCEPROP 2 LAST SIG_NAME HDT_HDR_TMS
J 0
(-4250 4185);
DISPLAY 0.489362 (-4250 4185);
WIRE 16 -1 (-3625 4075)(-4325 4075);
FORCEPROP 2 LAST SIG_NAME HDT_HDR_DBREQ_N
J 0
(-4250 4085);
DISPLAY 0.489362 (-4250 4085);
WIRE 16 -1 (-3650 2025)(-4325 2025);
FORCEPROP 2 LAST SIG_NAME JTAG_SCM_MUX_TMS
J 0
(-4325 2035);
DISPLAY 0.489362 (-4325 2035);
WIRE 16 -1 (-3650 1975)(-4325 1975);
FORCEPROP 2 LAST SIG_NAME JTAG_SCM_TRST_N
J 0
(-4325 1985);
DISPLAY 0.489362 (-4325 1985);
WIRE 16 -1 (-3650 1925)(-4325 1925);
FORCEPROP 2 LAST SIG_NAME JTAG_SCM_DBREQ_N
J 0
(-4325 1935);
DISPLAY 0.489362 (-4325 1935);
WIRE 16 -1 (-3650 2075)(-4325 2075);
FORCEPROP 2 LAST SIG_NAME JTAG_SCM_MUX_TCK
J 0
(-4325 2085);
DISPLAY 0.489362 (-4325 2085);
WIRE 16 -1 (-8250 4125)(-7425 4125);
FORCEPROP 2 LAST SIG_NAME HDT_HDR_TDI
J 2
(-7910 4135);
DISPLAY 0.489362 (-7910 4135);
WIRE 16 -1 (-4875 5850)(-4075 5850);
FORCEPROP 2 LAST SIG_NAME HDT_HDR_R_TDI
J 0
(-4550 5860);
DISPLAY 0.489362 (-4550 5860);
FORCEPROP 2 LASTPROP $XRERR UNIQUE?
J 0
(-4790 5860);
DISPLAY 0.638298 (-4790 5860);
PAINT MONO (-4790 5860);
DISPLAY INVISIBLE (-4790 5860);
WIRE 16 -1 (-4875 5900)(-4075 5900);
FORCEPROP 2 LAST SIG_NAME HDT_HDR_R_TMS
J 0
(-4550 5910);
DISPLAY 0.489362 (-4550 5910);
FORCEPROP 2 LASTPROP $XRERR UNIQUE?
J 0
(-4790 5910);
DISPLAY 0.638298 (-4790 5910);
PAINT MONO (-4790 5910);
DISPLAY INVISIBLE (-4790 5910);
WIRE 16 -1 (-4075 5950)(-4875 5950);
FORCEPROP 2 LAST SIG_NAME HDT_HDR_R_TCK
J 0
(-4550 5960);
DISPLAY 0.489362 (-4550 5960);
FORCEPROP 2 LASTPROP $XRERR UNIQUE?
J 0
(-4790 5960);
DISPLAY 0.638298 (-4790 5960);
PAINT MONO (-4790 5960);
DISPLAY INVISIBLE (-4790 5960);
WIRE 16 -1 (-8300 3975)(-7425 3975);
FORCEPROP 2 LAST SIG_NAME HDT_HDR_TDO_R
J 0
(-8160 3985);
DISPLAY 0.489362 (-8160 3985);
FORCEPROP 2 LASTPROP $XRERR UNIQUE?
J 0
(-8400 3985);
DISPLAY 0.638298 (-8400 3985);
PAINT MONO (-8400 3985);
DISPLAY INVISIBLE (-8400 3985);
WIRE 16 -1 (-5150 3925)(-5575 3925);
FORCEPROP 2 LAST SIG_NAME JTAG_TDO
J 2
(-5235 3935);
DISPLAY 0.489362 (-5235 3935);
WIRE 16 -1 (-3875 5950)(-3650 5950);
WIRE 16 -1 (-3650 5950)(-2800 5950);
WIRE 16 -1 (-3650 6025)(-3650 5950);
WIRE 16 -1 (-1700 5950)(-2800 5950);
FORCEPROP 2 LAST SIG_NAME HDT_HDR_TCK
J 0
(-2135 5960);
DISPLAY 0.489362 (-2135 5960);
WIRE 16 -1 (-2800 5950)(-2800 5425);
WIRE 16 -1 (-3150 6025)(-3150 5600);
WIRE 16 -1 (-3150 5600)(-3125 5600);
WIRE 16 -1 (-4875 5600)(-3150 5600);
FORCEPROP 2 LAST SIG_NAME HDT_HDR_DBREQ_R_N
J 0
(-4550 5610);
DISPLAY 0.489362 (-4550 5610);
FORCEPROP 2 LASTPROP $XRERR UNIQUE?
J 0
(-4790 5610);
DISPLAY 0.638298 (-4790 5610);
PAINT MONO (-4790 5610);
DISPLAY INVISIBLE (-4790 5610);
WIRE 16 -1 (-3125 5550)(-3675 5550);
WIRE 16 -1 (-3675 5550)(-3675 5425);
WIRE 16 -1 (-4875 5550)(-3675 5550);
FORCEPROP 2 LAST SIG_NAME HDT_CPU0_HDT_CONN_TESTEN
J 0
(-4550 5560);
DISPLAY 0.489362 (-4550 5560);
FORCEPROP 2 LASTPROP $XRERR UNIQUE?
J 0
(-4790 5560);
DISPLAY 0.638298 (-4790 5560);
PAINT MONO (-4790 5560);
DISPLAY INVISIBLE (-4790 5560);
WIRE 16 -1 (-6200 5650)(-5375 5650);
FORCEPROP 2 LAST SIG_NAME HDT_CPU0_XTRIG_L7
J 2
(-5650 5660);
DISPLAY 0.489362 (-5650 5660);
FORCEPROP 2 LASTPROP $XRERR UNIQUE?
J 0
(-5890 5660);
DISPLAY 0.638298 (-5890 5660);
PAINT MONO (-5890 5660);
DISPLAY INVISIBLE (-5890 5660);
WIRE 16 -1 (-6400 5650)(-7075 5650);
FORCEPROP 2 LAST SIG_NAME CPU0_XTRIG_L7
J 0
(-6925 5660);
DISPLAY 0.489362 (-6925 5660);
WIRE 16 -1 (-6200 5700)(-5375 5700);
FORCEPROP 2 LAST SIG_NAME HDT_CPU0_XTRIG_L6
J 2
(-5650 5710);
DISPLAY 0.489362 (-5650 5710);
FORCEPROP 2 LASTPROP $XRERR UNIQUE?
J 0
(-5890 5710);
DISPLAY 0.638298 (-5890 5710);
PAINT MONO (-5890 5710);
DISPLAY INVISIBLE (-5890 5710);
WIRE 16 -1 (-6400 5700)(-7075 5700);
FORCEPROP 2 LAST SIG_NAME CPU0_XTRIG_L6
J 0
(-6925 5710);
DISPLAY 0.489362 (-6925 5710);
WIRE 16 -1 (-6200 5750)(-6050 5750);
WIRE 16 -1 (-6050 6150)(-6050 5750);
WIRE 16 -1 (-5375 5750)(-6050 5750);
FORCEPROP 2 LAST SIG_NAME HDT_HDR_TRST_N_R
J 2
(-5650 5760);
DISPLAY 0.489362 (-5650 5760);
FORCEPROP 2 LASTPROP $XRERR UNIQUE?
J 0
(-5890 5760);
DISPLAY 0.638298 (-5890 5760);
PAINT MONO (-5890 5760);
DISPLAY INVISIBLE (-5890 5760);
WIRE 16 -1 (-7000 5750)(-6400 5750);
FORCEPROP 2 LAST SIG_NAME HDT_HDR_TRST_N
J 0
(-6925 5760);
DISPLAY 0.489362 (-6925 5760);
WIRE 16 -1 (-7100 5750)(-7000 5750);
WIRE 16 -1 (-7000 5750)(-7000 5475);
WIRE 16 -1 (-6200 5600)(-5375 5600);
FORCEPROP 2 LAST SIG_NAME HDT_CPU0_XTRIG_L5
J 2
(-5650 5610);
DISPLAY 0.489362 (-5650 5610);
FORCEPROP 2 LASTPROP $XRERR UNIQUE?
J 0
(-5890 5610);
DISPLAY 0.638298 (-5890 5610);
PAINT MONO (-5890 5610);
DISPLAY INVISIBLE (-5890 5610);
WIRE 16 -1 (-6400 5600)(-7075 5600);
FORCEPROP 2 LAST SIG_NAME CPU0_XTRIG_L5
J 0
(-6925 5610);
DISPLAY 0.489362 (-6925 5610);
WIRE 16 -1 (-6200 5900)(-5375 5900);
FORCEPROP 2 LAST SIG_NAME PRSNT_HDT_R_N
J 0
(-6035 5910);
DISPLAY 0.489362 (-6035 5910);
FORCEPROP 2 LASTPROP $XRERR UNIQUE?
J 0
(-6275 5910);
DISPLAY 0.638298 (-6275 5910);
PAINT MONO (-6275 5910);
DISPLAY INVISIBLE (-6275 5910);
WIRE 16 -1 (-7100 5900)(-6400 5900);
FORCEPROP 2 LAST SIG_NAME PRSNT_HDT_N
J 0
(-6925 5910);
DISPLAY 0.489362 (-6925 5910);
WIRE 16 -1 (-1125 3875)(-1125 4125);
WIRE 16 -1 (-575 4125)(-1125 4125);
WIRE 16 -1 (-1575 4125)(-1125 4125);
FORCEPROP 2 LAST SIG_NAME JTAG_TRST_N
J 0
(-1435 4135);
DISPLAY 0.489362 (-1435 4135);
WIRE 16 -1 (-2850 1975)(-2175 1975);
WIRE 16 -1 (-2175 1975)(-2175 4125);
WIRE 16 -1 (-1775 4125)(-2175 4125);
WIRE 16 -1 (-2825 4125)(-2175 4125);
FORCEPROP 2 LAST SIG_NAME JTAG_TRST_R_N
J 0
(-2725 4135);
DISPLAY 0.489362 (-2725 4135);
FORCEPROP 2 LASTPROP $XRERR UNIQUE?
J 0
(-2965 4135);
DISPLAY 0.638298 (-2965 4135);
PAINT MONO (-2965 4135);
DISPLAY INVISIBLE (-2965 4135);
WIRE 16 -1 (-800 3875)(-800 4075);
WIRE 16 -1 (-575 4075)(-800 4075);
WIRE 16 -1 (-1575 4075)(-800 4075);
FORCEPROP 2 LAST SIG_NAME JTAG_DBREQ_N
J 0
(-1435 4085);
DISPLAY 0.489362 (-1435 4085);
WIRE 16 -1 (-2850 1925)(-2125 1925);
WIRE 16 -1 (-2125 1925)(-2125 4075);
WIRE 16 -1 (-1775 4075)(-2125 4075);
WIRE 16 -1 (-2825 4075)(-2125 4075);
FORCEPROP 2 LAST SIG_NAME JTAG_DBREQ_R_N
J 0
(-2725 4085);
DISPLAY 0.489362 (-2725 4085);
FORCEPROP 2 LASTPROP $XRERR UNIQUE?
J 0
(-2965 4085);
DISPLAY 0.638298 (-2965 4085);
PAINT MONO (-2965 4085);
DISPLAY INVISIBLE (-2965 4085);
WIRE 16 -1 (-8925 3975)(-8500 3975);
FORCEPROP 2 LAST SIG_NAME HDT_HDR_TDO
J 0
(-8885 3985);
DISPLAY 0.489362 (-8885 3985);
WIRE 16 -1 (-8675 2225)(-7400 2225);
FORCEPROP 2 LAST SIG_NAME JTAG_SCM_MUX_TDO
J 2
(-7860 2235);
DISPLAY 0.489362 (-7860 2235);
WIRE 16 -1 (-8675 2075)(-7400 2075);
FORCEPROP 2 LAST SIG_NAME JTAG_SCM_MUX_TDI
J 2
(-7860 2085);
DISPLAY 0.489362 (-7860 2085);
WIRE 16 -1 (-7600 1925)(-7400 1925);
WIRE 16 -1 (-7600 1925)(-7600 1575);
WIRE 16 -1 (-7600 1575)(-6600 1575);
WIRE 16 -1 (-6600 1575)(-3650 1575);
WIRE 16 -1 (-6600 950)(-6600 1575);
WIRE 16 -1 (-7475 950)(-6600 950);
FORCEPROP 2 LAST SIG_NAME JTAG_BMC_OE_N
J 2
(-6960 960);
DISPLAY 0.489362 (-6960 960);
FORCEPROP 2 LASTPROP $XRERR UNIQUE?
J 0
(-7200 960);
DISPLAY 0.638298 (-7200 960);
PAINT MONO (-7200 960);
DISPLAY INVISIBLE (-7200 960);
WIRE 16 -1 (-7475 950)(-7475 1100);
WIRE 16 -1 (-7475 800)(-7475 950);
WIRE 16 -1 (-6600 2025)(-5900 2025);
WIRE 16 -1 (-5900 2025)(-5900 3925);
WIRE 16 -1 (-5775 3925)(-5900 3925);
WIRE 16 -1 (-6625 3925)(-5900 3925);
FORCEPROP 2 LAST SIG_NAME JTAG_TDO_R1
J 2
(-6135 3935);
DISPLAY 0.489362 (-6135 3935);
FORCEPROP 2 LASTPROP $XRERR UNIQUE?
J 0
(-6375 3935);
DISPLAY 0.638298 (-6375 3935);
PAINT MONO (-6375 3935);
DISPLAY INVISIBLE (-6375 3935);
WIRE 16 -1 (-6600 2175)(-5950 2175);
WIRE 16 -1 (-5950 2175)(-5950 4075);
WIRE 16 -1 (-5775 4075)(-5950 4075);
WIRE 16 -1 (-6625 4075)(-5950 4075);
FORCEPROP 2 LAST SIG_NAME JTAG_TDI_R
J 2
(-6160 4085);
DISPLAY 0.489362 (-6160 4085);
FORCEPROP 2 LASTPROP $XRERR UNIQUE?
J 0
(-6400 4085);
DISPLAY 0.638298 (-6400 4085);
PAINT MONO (-6400 4085);
DISPLAY INVISIBLE (-6400 4085);
WIRE 16 -1 (-8500 3350)(-8425 3350);
WIRE 16 -1 (-8500 600)(-8500 3350);
WIRE 16 -1 (-8500 600)(-7625 600);
FORCEPROP 2 LAST SIG_NAME JTAG_BMC_OE
J 2
(-8060 610);
DISPLAY 0.489362 (-8060 610);
WIRE 16 -1 (-8500 600)(-8600 600);
WIRE 16 -1 (-7500 3825)(-7425 3825);
WIRE 16 -1 (-7500 3825)(-7500 3350);
WIRE 16 -1 (-6425 3350)(-7500 3350);
FORCEPROP 2 LAST SIG_NAME JTAG_BMC_R_D_OE
J 2
(-6960 3360);
DISPLAY 0.489362 (-6960 3360);
FORCEPROP 2 LASTPROP $XRERR UNIQUE?
J 0
(-7200 3360);
DISPLAY 0.638298 (-7200 3360);
PAINT MONO (-7200 3360);
DISPLAY INVISIBLE (-7200 3360);
WIRE 16 -1 (-7500 3350)(-8075 3350);
WIRE 16 -1 (-8075 3250)(-8075 3350);
WIRE 16 -1 (-8075 3350)(-8225 3350);
WIRE 16 -1 (-4325 3350)(-6425 3350);
WIRE 16 -1 (-6425 3450)(-6425 3350);
WIRE 16 -1 (-4325 3350)(-4325 3725);
WIRE 16 -1 (-4325 3725)(-3625 3725);
DOT 1 (-8075 3350);
DOT 1 (-3750 2550);
DOT 1 (-6050 5750);
DOT 1 (-6450 2900);
DOT 1 (-6475 4700);
DOT 1 (-1500 4225);
DOT 1 (-6425 3350);
DOT 1 (-7475 950);
DOT 1 (-6600 1575);
DOT 1 (-8500 600);
DOT 1 (-6475 4800);
DOT 1 (-7750 1775);
DOT 1 (-1125 4125);
DOT 1 (-6475 4325);
DOT 1 (-3275 6300);
DOT 1 (-3400 6300);
DOT 1 (-3525 6300);
DOT 1 (-3650 6300);
DOT 1 (-3275 5800);
DOT 1 (-3400 5850);
DOT 1 (-3525 5900);
DOT 1 (-3650 5950);
DOT 1 (-800 4075);
DOT 1 (-3675 5550);
DOT 1 (-2800 5950);
DOT 1 (-2125 5550);
DOT 1 (-2575 5850);
DOT 1 (-3150 5600);
DOT 1 (-2225 4175);
DOT 1 (-2275 4225);
DOT 1 (-2175 4125);
DOT 1 (-2125 4075);
DOT 1 (-2725 2825);
DOT 1 (-2725 4725);
DOT 1 (-3750 4700);
DOT 1 (-3750 1775);
DOT 1 (-3750 1725);
DOT 1 (-3750 1675);
DOT 1 (-3750 3925);
DOT 1 (-3750 3875);
DOT 1 (-3750 3825);
DOT 1 (-3750 4425);
DOT 1 (-3750 2275);
DOT 1 (-5475 5800);
DOT 1 (-5600 5950);
DOT 1 (-7000 5750);
DOT 1 (-5475 5550);
DOT 1 (-5900 3925);
DOT 1 (-5425 4075);
DOT 1 (-5950 4075);
DOT 1 (-7650 3675);
DOT 1 (-7500 3350);
DOT 1 (-7450 2800);
DOT 1 (-7625 2975);
DOT 1 (-2350 5600);
FORCENOTE
TO JTAG BUF
(-1475 4350) 0;
DISPLAY LEFT (-1475 4350);
DISPLAY 2.510638 (-1475 4350);
PAINT WHITE (-1475 4350);
FORCENOTE
HDT
(-8925 4350) 0;
DISPLAY LEFT (-8925 4350);
DISPLAY 2.510638 (-8925 4350);
PAINT WHITE (-8925 4350);
FORCENOTE
L:HDT
(-9150 1000) 0;
DISPLAY LEFT (-9150 1000);
DISPLAY 2.510638 (-9150 1000);
PAINT WHITE (-9150 1000);
FORCENOTE
H:BMC
(-9150 775) 0;
DISPLAY LEFT (-9150 775);
DISPLAY 2.510638 (-9150 775);
PAINT WHITE (-9150 775);
FORCENOTE
BMC 
(-9025 2450) 0;
DISPLAY LEFT (-9025 2450);
DISPLAY 2.510638 (-9025 2450);
PAINT WHITE (-9025 2450);
QUIT
